FILE_TYPE = MACRO_DRAWING;
SET COLOR_WIRE YELLOW;
SET COLOR_PROP ORANGE;
SET COLOR_DOT WHITE;
SET COLOR_ARC YELLOW;
SET COLOR_BODY GREEN;
SET COLOR_NOTE PURPLE;
SET PROP_DISPLAY VALUE;
SET PAGE_NUMBER P462;
FORCEADD OFFPAGE..1
R 2
(-2450 2700);
FORCEPROP 2 LAST $XR0 354 
J 0
(-2264 2700);
DISPLAY 0.638298 (-2264 2700);
PAINT MONO (-2264 2700);
FORCEPROP 2 LAST CDS_LIB standard
J 0
(-2450 2700);
DISPLAY INVISIBLE (-2450 2700);
FORCEPROP 1 LAST OFFPAGE TRUE
J 2
(-2775 2575);
DISPLAY 0.872340 (-2775 2575);
DISPLAY INVISIBLE (-2775 2575);
FORCEPROP 1 LAST COMMENT_BODY TRUE
J 2
(-2575 2600);
DISPLAY 0.872340 (-2575 2600);
PAINT GREEN (-2575 2600);
DISPLAY INVISIBLE (-2575 2600);
FORCEPROP 2 LAST PATH I100
J 0
(-2275 2775);
DISPLAY 0.680851 (-2275 2775);
DISPLAY INVISIBLE (-2275 2775);
FORCEADD Q_RES..1
(-2750 3250);
FORCEPROP 1 LAST LOCATION R1429
J 0
(-2875 3250);
DISPLAY 0.787234 (-2875 3250);
PAINT WHITE (-2875 3250);
FORCEPROP 0 LAST $SEC 1
J 0
(-2375 3300);
DISPLAY 0.680851 (-2375 3300);
PAINT MONO (-2375 3300);
DISPLAY INVISIBLE (-2375 3300);
FORCEPROP 0 LAST CDS_SEC 1
J 0
(-2375 3300);
DISPLAY 0.680851 (-2375 3300);
DISPLAY INVISIBLE (-2375 3300);
FORCEPROP 1 LASTPIN (-2850 3250) $PN 1
J 0
(-2838 3262);
DISPLAY 0.787234 (-2838 3262);
PAINT MONO (-2838 3262);
FORCEPROP 1 LASTPIN (-2650 3250) $PN 2
J 0
(-2688 3262);
DISPLAY 0.787234 (-2688 3262);
PAINT MONO (-2688 3262);
FORCEPROP 1 LAST MATERIAL CHIP
J 0
(-2525 3250);
DISPLAY 0.638298 (-2525 3250);
FORCEPROP 1 LAST VALUE 1K
J 2
(-2550 3250);
DISPLAY 0.638298 (-2550 3250);
FORCEPROP 1 LAST PACK_TYPE 0201LF
J 0
(-2375 3250);
DISPLAY 0.638298 (-2375 3250);
FORCEPROP 2 LAST CDS_LIB pure_quanta
J 0
(-2750 3250);
DISPLAY INVISIBLE (-2750 3250);
FORCEPROP 1 LAST WATTAGE 1/20W
J 2
(-2775 3100);
DISPLAY 0.638298 (-2775 3100);
DISPLAY INVISIBLE (-2775 3100);
FORCEPROP 1 LAST TOLERANCE 1%
J 0
(-2750 3150);
DISPLAY 0.638298 (-2750 3150);
DISPLAY INVISIBLE (-2750 3150);
FORCEPROP 1 LAST PATH I103
J 0
(-2800 3400);
DISPLAY 0.978723 (-2800 3400);
PAINT WHITE (-2800 3400);
DISPLAY INVISIBLE (-2800 3400);
FORCEPROP 1 LAST PART_NUMBER CS21001FE07
J 0
(-2800 3350);
DISPLAY 0.978723 (-2800 3350);
DISPLAY INVISIBLE (-2800 3350);
FORCEADD UNIVERSAL_GND..1
R 1
(-2000 2300);
FORCEPROP 3 LASTPIN (-2050 2300) SIG_NAME GND\g
J 0
(-2040 2310);
DISPLAY 0.659574 (-2040 2310);
PAINT MONO (-2040 2310);
DISPLAY INVISIBLE (-2040 2310);
FORCEPROP 2 LAST CDS_LIB pure_quanta_power
J 0
(-2000 2300);
DISPLAY INVISIBLE (-2000 2300);
FORCEPROP 1 LAST HDL_POWER GND
R 1
J 1
(-1925 2325);
DISPLAY 0.872340 (-1925 2325);
PAINT GREEN (-1925 2325);
DISPLAY INVISIBLE (-1925 2325);
FORCEPROP 1 LAST PATH I107
R 1
J 0
(-2000 2375);
DISPLAY 0.872340 (-2000 2375);
PAINT AQUA (-2000 2375);
DISPLAY INVISIBLE (-2000 2375);
FORCEADD GND..1
(-1525 2800);
FORCEPROP 3 LASTPIN (-1525 2850) SIG_NAME GND\g
J 0
(-1515 2860);
DISPLAY 0.659574 (-1515 2860);
PAINT MONO (-1515 2860);
DISPLAY INVISIBLE (-1515 2860);
FORCEPROP 2 LAST BOM_COST MEM
J 0
(-1625 2875);
DISPLAY 0.808511 (-1625 2875);
DISPLAY INVISIBLE (-1625 2875);
FORCEPROP 1 LAST SIZE 1B
J 0
(-1450 2750);
DISPLAY 0.851064 (-1450 2750);
PAINT GREEN (-1450 2750);
DISPLAY INVISIBLE (-1450 2750);
FORCEPROP 2 LAST CDS_LIB pure_quanta_power
J 0
(-1525 2800);
DISPLAY INVISIBLE (-1525 2800);
FORCEPROP 1 LAST HDL_POWER GND
J 0
(-1525 2950);
DISPLAY 0.851064 (-1525 2950);
PAINT GREEN (-1525 2950);
DISPLAY INVISIBLE (-1525 2950);
FORCEPROP 1 LAST PATH I108
J 0
(-1450 2800);
DISPLAY 0.872340 (-1450 2800);
PAINT AQUA (-1450 2800);
DISPLAY INVISIBLE (-1450 2800);
FORCEADD UNIVERSAL_GND..1
R 1
(-2000 3250);
FORCEPROP 3 LASTPIN (-2050 3250) SIG_NAME GND\g
J 0
(-2040 3260);
DISPLAY 0.659574 (-2040 3260);
PAINT MONO (-2040 3260);
DISPLAY INVISIBLE (-2040 3260);
FORCEPROP 2 LAST CDS_LIB pure_quanta_power
J 0
(-2000 3250);
DISPLAY INVISIBLE (-2000 3250);
FORCEPROP 1 LAST HDL_POWER GND
R 1
J 1
(-1925 3275);
DISPLAY 0.872340 (-1925 3275);
PAINT GREEN (-1925 3275);
DISPLAY INVISIBLE (-1925 3275);
FORCEPROP 1 LAST PATH I110
R 1
J 0
(-2000 3325);
DISPLAY 0.872340 (-2000 3325);
PAINT AQUA (-2000 3325);
DISPLAY INVISIBLE (-2000 3325);
FORCEADD Q_RES..2
(-1525 3200);
FORCEPROP 1 LAST LOCATION R1435
J 0
(-1480 3325);
DISPLAY 0.787234 (-1480 3325);
PAINT WHITE (-1480 3325);
FORCEPROP 0 LAST $SEC 1
J 0
(-1475 3375);
DISPLAY 0.680851 (-1475 3375);
PAINT MONO (-1475 3375);
DISPLAY INVISIBLE (-1475 3375);
FORCEPROP 0 LAST CDS_SEC 1
J 0
(-1475 3375);
DISPLAY 0.680851 (-1475 3375);
DISPLAY INVISIBLE (-1475 3375);
FORCEPROP 1 LASTPIN (-1525 3300) $PN 1
J 0
(-1520 3262);
DISPLAY 0.787234 (-1520 3262);
PAINT MONO (-1520 3262);
FORCEPROP 1 LASTPIN (-1525 3100) $PN 2
J 0
(-1520 3110);
DISPLAY 0.787234 (-1520 3110);
PAINT MONO (-1520 3110);
FORCEPROP 1 LAST PACK_TYPE 0201LF
J 0
(-1485 3025);
DISPLAY 0.787234 (-1485 3025);
FORCEPROP 1 LAST WATTAGE 1/20W
J 0
(-1485 3175);
DISPLAY 0.787234 (-1485 3175);
FORCEPROP 1 LAST VALUE 10K
J 0
(-1480 3275);
DISPLAY 0.787234 (-1480 3275);
FORCEPROP 1 LAST TOLERANCE 1%
J 0
(-1480 3225);
DISPLAY 0.787234 (-1480 3225);
FORCEPROP 1 LAST MATERIAL CHIP
J 0
(-1485 3125);
DISPLAY 0.787234 (-1485 3125);
FORCEPROP 2 LAST CDS_LIB pure_quanta
J 0
(-1525 3200);
DISPLAY INVISIBLE (-1525 3200);
FORCEPROP 1 LAST PATH I114
J 0
(-1475 3375);
DISPLAY 0.978723 (-1475 3375);
PAINT WHITE (-1475 3375);
DISPLAY INVISIBLE (-1475 3375);
FORCEPROP 1 LAST PART_NUMBER CS31001FE17
J 0
(-1485 3075);
DISPLAY 0.510638 (-1485 3075);
DISPLAY INVISIBLE (-1485 3075);
FORCEADD Q_RES..2
(-1525 3725);
FORCEPROP 1 LAST LOCATION R1434
J 0
(-1480 3850);
DISPLAY 0.787234 (-1480 3850);
PAINT WHITE (-1480 3850);
FORCEPROP 0 LAST $SEC 1
J 0
(-1475 3900);
DISPLAY 0.680851 (-1475 3900);
PAINT MONO (-1475 3900);
DISPLAY INVISIBLE (-1475 3900);
FORCEPROP 0 LAST CDS_SEC 1
J 0
(-1475 3900);
DISPLAY 0.680851 (-1475 3900);
DISPLAY INVISIBLE (-1475 3900);
FORCEPROP 1 LASTPIN (-1525 3825) $PN 1
J 0
(-1520 3787);
DISPLAY 0.787234 (-1520 3787);
PAINT MONO (-1520 3787);
FORCEPROP 1 LASTPIN (-1525 3625) $PN 2
J 0
(-1520 3635);
DISPLAY 0.787234 (-1520 3635);
PAINT MONO (-1520 3635);
FORCEPROP 1 LAST TOLERANCE 1%
J 0
(-1480 3750);
DISPLAY 0.787234 (-1480 3750);
FORCEPROP 1 LAST WATTAGE 1/20W
J 0
(-1485 3700);
DISPLAY 0.787234 (-1485 3700);
FORCEPROP 1 LAST PACK_TYPE 0201LF
J 0
(-1485 3550);
DISPLAY 0.787234 (-1485 3550);
FORCEPROP 1 LAST MATERIAL EMPTY
J 0
(-1485 3650);
DISPLAY 0.787234 (-1485 3650);
PAINT RED (-1485 3650);
FORCEPROP 1 LAST VALUE 1K
J 0
(-1480 3800);
DISPLAY 0.787234 (-1480 3800);
FORCEPROP 2 LAST CDS_LIB pure_quanta
J 0
(-1525 3725);
DISPLAY INVISIBLE (-1525 3725);
FORCEPROP 1 LAST PATH I115
J 0
(-1475 3900);
DISPLAY 0.978723 (-1475 3900);
PAINT WHITE (-1475 3900);
DISPLAY INVISIBLE (-1475 3900);
FORCEPROP 1 LAST PART_NUMBER CS21001FE07
J 0
(-1485 3600);
DISPLAY 0.978723 (-1485 3600);
DISPLAY INVISIBLE (-1485 3600);
FORCEADD OFFPAGE..1
R 2
(-675 3450);
FORCEPROP 2 LAST $XR0 354 
J 0
(-489 3450);
DISPLAY 0.638298 (-489 3450);
PAINT MONO (-489 3450);
FORCEPROP 2 LAST CDS_LIB standard
J 0
(-675 3450);
DISPLAY INVISIBLE (-675 3450);
FORCEPROP 1 LAST OFFPAGE TRUE
J 2
(-1000 3325);
DISPLAY 0.872340 (-1000 3325);
DISPLAY INVISIBLE (-1000 3325);
FORCEPROP 1 LAST COMMENT_BODY TRUE
J 2
(-800 3350);
DISPLAY 0.872340 (-800 3350);
PAINT GREEN (-800 3350);
DISPLAY INVISIBLE (-800 3350);
FORCEPROP 2 LAST PATH I116
J 0
(-500 3525);
DISPLAY 0.680851 (-500 3525);
DISPLAY INVISIBLE (-500 3525);
FORCEADD P1V0..1
(-1525 4125);
FORCEPROP 3 LASTPIN (-1525 4075) SIG_NAME P1V8_CPU1_RT_1D\g
J 0
(-1515 4085);
DISPLAY 0.659574 (-1515 4085);
PAINT MONO (-1515 4085);
DISPLAY INVISIBLE (-1515 4085);
FORCEPROP 1 LAST HDL_POWER P1V8_CPU1_RT_1D
J 1
(-1525 4175);
DISPLAY 0.489362 (-1525 4175);
PAINT SKYBLUE (-1525 4175);
FORCEPROP 2 LAST CDS_LIB pure_quanta_power
J 0
(-1525 4125);
DISPLAY INVISIBLE (-1525 4125);
FORCEPROP 1 LAST PATH I117
J 0
(-1475 4150);
DISPLAY 0.872340 (-1475 4150);
PAINT AQUA (-1475 4150);
DISPLAY INVISIBLE (-1475 4150);
FORCEADD Q_RES..2
(-9025 3450);
FORCEPROP 1 LAST LOCATION R910
J 0
(-8980 3575);
DISPLAY 0.978723 (-8980 3575);
PAINT WHITE (-8980 3575);
FORCEPROP 0 LAST $SEC 1
J 0
(-8975 3625);
DISPLAY 0.680851 (-8975 3625);
PAINT MONO (-8975 3625);
DISPLAY INVISIBLE (-8975 3625);
FORCEPROP 0 LAST CDS_SEC 1
J 0
(-8975 3625);
DISPLAY 0.680851 (-8975 3625);
DISPLAY INVISIBLE (-8975 3625);
FORCEPROP 1 LASTPIN (-9025 3550) $PN 1
J 0
(-9020 3512);
DISPLAY 0.787234 (-9020 3512);
PAINT MONO (-9020 3512);
FORCEPROP 1 LASTPIN (-9025 3350) $PN 2
J 0
(-9020 3360);
DISPLAY 0.787234 (-9020 3360);
PAINT MONO (-9020 3360);
FORCEPROP 1 LAST PACK_TYPE 0201LF
J 0
(-8985 3275);
DISPLAY 0.978723 (-8985 3275);
FORCEPROP 1 LAST TOLERANCE 1%
J 0
(-8980 3475);
DISPLAY 0.978723 (-8980 3475);
FORCEPROP 1 LAST VALUE 200
J 0
(-8980 3525);
DISPLAY 0.978723 (-8980 3525);
FORCEPROP 1 LAST WATTAGE 1/20W
J 0
(-8985 3425);
DISPLAY 0.978723 (-8985 3425);
FORCEPROP 1 LAST MATERIAL CHIP
J 0
(-8985 3375);
DISPLAY 0.978723 (-8985 3375);
FORCEPROP 2 LAST CDS_LIB pure_quanta
J 0
(-9025 3450);
DISPLAY INVISIBLE (-9025 3450);
FORCEPROP 1 LAST PATH I119
J 0
(-8975 3625);
DISPLAY 0.978723 (-8975 3625);
PAINT WHITE (-8975 3625);
DISPLAY INVISIBLE (-8975 3625);
FORCEPROP 1 LAST PART_NUMBER CS12001FE12
J 0
(-8985 3325);
DISPLAY 0.978723 (-8985 3325);
DISPLAY INVISIBLE (-8985 3325);
FORCEADD OFFPAGE..5
(-2550 1000);
FORCEPROP 2 LAST $XR0 354 
J 0
(-2835 1000);
DISPLAY 0.638298 (-2835 1000);
PAINT MONO (-2835 1000);
FORCEPROP 2 LAST CDS_LIB standard
J 0
(-2550 1000);
DISPLAY INVISIBLE (-2550 1000);
FORCEPROP 1 LAST OFFPAGE TRUE
J 0
(-2225 875);
DISPLAY 0.872340 (-2225 875);
PAINT GREEN (-2225 875);
DISPLAY INVISIBLE (-2225 875);
FORCEPROP 1 LAST COMMENT_BODY TRUE
J 0
(-2450 925);
DISPLAY 0.872340 (-2450 925);
PAINT GREEN (-2450 925);
DISPLAY INVISIBLE (-2450 925);
FORCEPROP 2 LAST PATH I121
J 0
(-2500 1075);
DISPLAY 0.680851 (-2500 1075);
DISPLAY INVISIBLE (-2500 1075);
FORCEADD OFFPAGE..5
(-2550 950);
FORCEPROP 2 LAST $XR0 354 
J 0
(-2835 950);
DISPLAY 0.638298 (-2835 950);
PAINT MONO (-2835 950);
FORCEPROP 2 LAST CDS_LIB standard
J 0
(-2550 950);
DISPLAY INVISIBLE (-2550 950);
FORCEPROP 1 LAST OFFPAGE TRUE
J 0
(-2225 825);
DISPLAY 0.872340 (-2225 825);
PAINT GREEN (-2225 825);
DISPLAY INVISIBLE (-2225 825);
FORCEPROP 1 LAST COMMENT_BODY TRUE
J 0
(-2450 875);
DISPLAY 0.872340 (-2450 875);
PAINT GREEN (-2450 875);
DISPLAY INVISIBLE (-2450 875);
FORCEPROP 2 LAST PATH I122
J 0
(-2500 1025);
DISPLAY 0.680851 (-2500 1025);
DISPLAY INVISIBLE (-2500 1025);
FORCEADD OFFPAGE..5
(-2550 1050);
FORCEPROP 2 LAST $XR0 354 
J 0
(-2835 1050);
DISPLAY 0.638298 (-2835 1050);
PAINT MONO (-2835 1050);
FORCEPROP 2 LAST CDS_LIB standard
J 0
(-2550 1050);
DISPLAY INVISIBLE (-2550 1050);
FORCEPROP 1 LAST OFFPAGE TRUE
J 0
(-2225 925);
DISPLAY 0.872340 (-2225 925);
PAINT GREEN (-2225 925);
DISPLAY INVISIBLE (-2225 925);
FORCEPROP 1 LAST COMMENT_BODY TRUE
J 0
(-2450 975);
DISPLAY 0.872340 (-2450 975);
PAINT GREEN (-2450 975);
DISPLAY INVISIBLE (-2450 975);
FORCEPROP 2 LAST PATH I123
J 0
(-2500 1125);
DISPLAY 0.680851 (-2500 1125);
DISPLAY INVISIBLE (-2500 1125);
FORCEADD OFFPAGE..5
(-2550 1100);
FORCEPROP 2 LAST $XR0 354 
J 0
(-2835 1100);
DISPLAY 0.638298 (-2835 1100);
PAINT MONO (-2835 1100);
FORCEPROP 2 LAST CDS_LIB standard
J 2
(-2550 1100);
DISPLAY INVISIBLE (-2550 1100);
FORCEPROP 1 LAST OFFPAGE TRUE
J 0
(-2225 975);
DISPLAY 0.872340 (-2225 975);
PAINT GREEN (-2225 975);
DISPLAY INVISIBLE (-2225 975);
FORCEPROP 1 LAST COMMENT_BODY TRUE
J 0
(-2450 1025);
DISPLAY 0.872340 (-2450 1025);
PAINT GREEN (-2450 1025);
DISPLAY INVISIBLE (-2450 1025);
FORCEPROP 2 LAST PATH I124
J 0
(-2500 1175);
DISPLAY 0.680851 (-2500 1175);
DISPLAY INVISIBLE (-2500 1175);
FORCEADD Q_RES..2
(-1125 1350);
FORCEPROP 1 LAST LOCATION R1511
J 0
(-1080 1475);
DISPLAY 0.978723 (-1080 1475);
FORCEPROP 0 LAST $SEC 1
J 0
(-1075 1525);
DISPLAY 0.680851 (-1075 1525);
PAINT MONO (-1075 1525);
DISPLAY INVISIBLE (-1075 1525);
FORCEPROP 0 LAST CDS_SEC 1
J 0
(-1075 1525);
DISPLAY 0.680851 (-1075 1525);
DISPLAY INVISIBLE (-1075 1525);
FORCEPROP 1 LASTPIN (-1125 1450) $PN 1
J 0
(-1120 1412);
DISPLAY 0.787234 (-1120 1412);
PAINT MONO (-1120 1412);
FORCEPROP 1 LASTPIN (-1125 1250) $PN 2
J 0
(-1120 1260);
DISPLAY 0.787234 (-1120 1260);
PAINT MONO (-1120 1260);
FORCEPROP 1 LAST MATERIAL EMPTY
J 0
(-1085 1275);
DISPLAY 0.787234 (-1085 1275);
PAINT RED (-1085 1275);
FORCEPROP 1 LAST PACK_TYPE 0201LF
J 0
(-1075 1200);
DISPLAY 0.787234 (-1075 1200);
FORCEPROP 1 LAST WATTAGE 1/20W
J 0
(-1085 1325);
DISPLAY 0.787234 (-1085 1325);
FORCEPROP 1 LAST TOLERANCE 5%
J 0
(-1080 1375);
DISPLAY 0.787234 (-1080 1375);
FORCEPROP 1 LAST VALUE 4.7K
J 0
(-1080 1425);
DISPLAY 0.787234 (-1080 1425);
FORCEPROP 2 LAST CDS_LIB pure_quanta
J 0
(-1125 1350);
DISPLAY INVISIBLE (-1125 1350);
FORCEPROP 1 LAST PATH I132
J 0
(-1075 1525);
DISPLAY 0.978723 (-1075 1525);
PAINT WHITE (-1075 1525);
DISPLAY INVISIBLE (-1075 1525);
FORCEPROP 1 LAST PART_NUMBER CS24701JE04
J 0
(-1085 1225);
DISPLAY 0.978723 (-1085 1225);
DISPLAY INVISIBLE (-1085 1225);
FORCEADD GND..1
(-575 425);
FORCEPROP 3 LASTPIN (-575 475) SIG_NAME GND\g
J 0
(-565 485);
DISPLAY 0.659574 (-565 485);
PAINT MONO (-565 485);
DISPLAY INVISIBLE (-565 485);
FORCEPROP 1 LAST SIZE 1B
J 0
(-500 375);
DISPLAY 0.851064 (-500 375);
PAINT GREEN (-500 375);
DISPLAY INVISIBLE (-500 375);
FORCEPROP 2 LAST BOM_COST MEM
J 0
(-675 500);
DISPLAY 0.808511 (-675 500);
DISPLAY INVISIBLE (-675 500);
FORCEPROP 2 LAST CDS_LIB pure_quanta_power
J 0
(-575 425);
DISPLAY INVISIBLE (-575 425);
FORCEPROP 1 LAST HDL_POWER GND
J 0
(-575 575);
DISPLAY 0.851064 (-575 575);
PAINT GREEN (-575 575);
DISPLAY INVISIBLE (-575 575);
FORCEPROP 1 LAST PATH I134
J 0
(-500 425);
DISPLAY 0.872340 (-500 425);
PAINT AQUA (-500 425);
DISPLAY INVISIBLE (-500 425);
FORCEADD Q_RES..2
(-575 725);
FORCEPROP 1 LAST LOCATION R1430
J 0
(-530 850);
DISPLAY 0.787234 (-530 850);
FORCEPROP 0 LAST $SEC 1
J 0
(-525 900);
DISPLAY 0.680851 (-525 900);
PAINT MONO (-525 900);
DISPLAY INVISIBLE (-525 900);
FORCEPROP 0 LAST CDS_SEC 1
J 0
(-525 900);
DISPLAY 0.680851 (-525 900);
DISPLAY INVISIBLE (-525 900);
FORCEPROP 1 LASTPIN (-575 825) $PN 1
J 0
(-570 787);
DISPLAY 0.787234 (-570 787);
PAINT MONO (-570 787);
FORCEPROP 1 LASTPIN (-575 625) $PN 2
J 0
(-570 635);
DISPLAY 0.787234 (-570 635);
PAINT MONO (-570 635);
FORCEPROP 1 LAST WATTAGE 1/20W
J 0
(-535 700);
DISPLAY 0.787234 (-535 700);
FORCEPROP 1 LAST VALUE 4.7K
J 0
(-530 800);
DISPLAY 0.787234 (-530 800);
FORCEPROP 1 LAST TOLERANCE 5%
J 0
(-530 750);
DISPLAY 0.787234 (-530 750);
FORCEPROP 1 LAST PACK_TYPE 0201LF
J 0
(-535 550);
DISPLAY 0.787234 (-535 550);
FORCEPROP 1 LAST MATERIAL CHIP
J 0
(-535 650);
DISPLAY 0.787234 (-535 650);
FORCEPROP 2 LAST CDS_LIB pure_quanta
J 0
(-575 725);
DISPLAY INVISIBLE (-575 725);
FORCEPROP 1 LAST PATH I136
J 0
(-525 900);
DISPLAY 0.978723 (-525 900);
PAINT WHITE (-525 900);
DISPLAY INVISIBLE (-525 900);
FORCEPROP 1 LAST PART_NUMBER CS24701JE04
J 0
(-535 600);
DISPLAY 0.978723 (-535 600);
DISPLAY INVISIBLE (-535 600);
FORCEADD Q_RES..2
(-575 1375);
FORCEPROP 1 LAST LOCATION R1513
J 0
(-530 1500);
DISPLAY 0.787234 (-530 1500);
FORCEPROP 0 LAST $SEC 1
J 0
(-525 1550);
DISPLAY 0.680851 (-525 1550);
PAINT MONO (-525 1550);
DISPLAY INVISIBLE (-525 1550);
FORCEPROP 0 LAST CDS_SEC 1
J 0
(-525 1550);
DISPLAY 0.680851 (-525 1550);
DISPLAY INVISIBLE (-525 1550);
FORCEPROP 1 LASTPIN (-575 1475) $PN 1
J 0
(-570 1437);
DISPLAY 0.787234 (-570 1437);
PAINT MONO (-570 1437);
FORCEPROP 1 LASTPIN (-575 1275) $PN 2
J 0
(-570 1285);
DISPLAY 0.787234 (-570 1285);
PAINT MONO (-570 1285);
FORCEPROP 1 LAST TOLERANCE 5%
J 0
(-530 1400);
DISPLAY 0.787234 (-530 1400);
FORCEPROP 1 LAST WATTAGE 1/20W
J 0
(-535 1350);
DISPLAY 0.787234 (-535 1350);
FORCEPROP 1 LAST VALUE 4.7K
J 0
(-530 1450);
DISPLAY 0.787234 (-530 1450);
FORCEPROP 1 LAST PACK_TYPE 0201LF
J 0
(-525 1225);
DISPLAY 0.787234 (-525 1225);
FORCEPROP 1 LAST MATERIAL EMPTY
J 0
(-535 1300);
DISPLAY 0.787234 (-535 1300);
PAINT RED (-535 1300);
FORCEPROP 2 LAST CDS_LIB pure_quanta
J 2
(-575 1375);
DISPLAY INVISIBLE (-575 1375);
FORCEPROP 1 LAST PATH I137
J 0
(-525 1550);
DISPLAY 0.978723 (-525 1550);
PAINT WHITE (-525 1550);
DISPLAY INVISIBLE (-525 1550);
FORCEPROP 1 LAST PART_NUMBER CS24701JE04
J 0
(-535 1250);
DISPLAY 0.978723 (-535 1250);
DISPLAY INVISIBLE (-535 1250);
FORCEADD P1V0..1
(-575 1675);
FORCEPROP 3 LASTPIN (-575 1625) SIG_NAME P1V8_CPU1_RT_1D\g
J 0
(-565 1635);
DISPLAY 0.659574 (-565 1635);
PAINT MONO (-565 1635);
DISPLAY INVISIBLE (-565 1635);
FORCEPROP 1 LAST HDL_POWER P1V8_CPU1_RT_1D
J 1
(-575 1725);
DISPLAY 0.489362 (-575 1725);
PAINT SKYBLUE (-575 1725);
FORCEPROP 2 LAST CDS_LIB pure_quanta_power
J 0
(-575 1675);
DISPLAY INVISIBLE (-575 1675);
FORCEPROP 1 LAST PATH I138
J 0
(-525 1700);
DISPLAY 0.872340 (-525 1700);
PAINT AQUA (-525 1700);
DISPLAY INVISIBLE (-525 1700);
FORCEADD Q_RES..2
(-1400 1350);
FORCEPROP 1 LAST LOCATION R1510
J 0
(-1355 1475);
DISPLAY 0.978723 (-1355 1475);
FORCEPROP 0 LAST $SEC 1
J 0
(-1350 1525);
DISPLAY 0.680851 (-1350 1525);
PAINT MONO (-1350 1525);
DISPLAY INVISIBLE (-1350 1525);
FORCEPROP 0 LAST CDS_SEC 1
J 0
(-1350 1525);
DISPLAY 0.680851 (-1350 1525);
DISPLAY INVISIBLE (-1350 1525);
FORCEPROP 1 LASTPIN (-1400 1450) $PN 1
J 0
(-1395 1412);
DISPLAY 0.787234 (-1395 1412);
PAINT MONO (-1395 1412);
FORCEPROP 1 LASTPIN (-1400 1250) $PN 2
J 0
(-1395 1260);
DISPLAY 0.787234 (-1395 1260);
PAINT MONO (-1395 1260);
FORCEPROP 1 LAST VALUE 4.7K
J 0
(-1355 1425);
DISPLAY 0.787234 (-1355 1425);
FORCEPROP 1 LAST PACK_TYPE 0201LF
J 0
(-1350 1200);
DISPLAY 0.787234 (-1350 1200);
FORCEPROP 1 LAST MATERIAL EMPTY
J 0
(-1360 1275);
DISPLAY 0.787234 (-1360 1275);
PAINT RED (-1360 1275);
FORCEPROP 1 LAST TOLERANCE 5%
J 0
(-1355 1375);
DISPLAY 0.787234 (-1355 1375);
FORCEPROP 1 LAST WATTAGE 1/20W
J 0
(-1360 1325);
DISPLAY 0.787234 (-1360 1325);
FORCEPROP 2 LAST CDS_LIB pure_quanta
J 0
(-1400 1350);
DISPLAY INVISIBLE (-1400 1350);
FORCEPROP 1 LAST PATH I139
J 0
(-1350 1525);
DISPLAY 0.978723 (-1350 1525);
PAINT WHITE (-1350 1525);
DISPLAY INVISIBLE (-1350 1525);
FORCEPROP 1 LAST PART_NUMBER CS24701JE04
J 0
(-1360 1225);
DISPLAY 0.978723 (-1360 1225);
DISPLAY INVISIBLE (-1360 1225);
FORCEADD Q_RES..2
(-850 1350);
FORCEPROP 1 LAST LOCATION R1512
J 0
(-805 1475);
DISPLAY 0.978723 (-805 1475);
FORCEPROP 0 LAST $SEC 1
J 0
(-800 1525);
DISPLAY 0.680851 (-800 1525);
PAINT MONO (-800 1525);
DISPLAY INVISIBLE (-800 1525);
FORCEPROP 0 LAST CDS_SEC 1
J 0
(-800 1525);
DISPLAY 0.680851 (-800 1525);
DISPLAY INVISIBLE (-800 1525);
FORCEPROP 1 LASTPIN (-850 1450) $PN 1
J 0
(-845 1412);
DISPLAY 0.787234 (-845 1412);
PAINT MONO (-845 1412);
FORCEPROP 1 LASTPIN (-850 1250) $PN 2
J 0
(-845 1260);
DISPLAY 0.787234 (-845 1260);
PAINT MONO (-845 1260);
FORCEPROP 1 LAST TOLERANCE 1%
J 0
(-805 1375);
DISPLAY 0.787234 (-805 1375);
FORCEPROP 1 LAST WATTAGE 1/20W
J 0
(-810 1325);
DISPLAY 0.787234 (-810 1325);
FORCEPROP 1 LAST VALUE 1K
J 0
(-805 1425);
DISPLAY 0.787234 (-805 1425);
FORCEPROP 1 LAST PACK_TYPE 0201LF
J 0
(-810 1175);
DISPLAY 0.787234 (-810 1175);
FORCEPROP 1 LAST MATERIAL EMPTY
J 0
(-810 1275);
DISPLAY 0.787234 (-810 1275);
PAINT RED (-810 1275);
FORCEPROP 2 LAST CDS_LIB pure_quanta
J 0
(-850 1350);
DISPLAY INVISIBLE (-850 1350);
FORCEPROP 1 LAST PATH I140
J 0
(-800 1525);
DISPLAY 0.978723 (-800 1525);
PAINT WHITE (-800 1525);
DISPLAY INVISIBLE (-800 1525);
FORCEPROP 1 LAST PART_NUMBER CS21001FE07
J 0
(-810 1225);
DISPLAY 0.978723 (-810 1225);
DISPLAY INVISIBLE (-810 1225);
FORCEADD OFFPAGE..1
R 2
(-2775 3650);
FORCEPROP 2 LAST $XR0 354 
J 0
(-2589 3650);
DISPLAY 0.638298 (-2589 3650);
PAINT MONO (-2589 3650);
FORCEPROP 2 LAST CDS_LIB standard
J 0
(-2775 3650);
DISPLAY INVISIBLE (-2775 3650);
FORCEPROP 1 LAST OFFPAGE TRUE
J 2
(-3100 3525);
DISPLAY 0.872340 (-3100 3525);
DISPLAY INVISIBLE (-3100 3525);
FORCEPROP 1 LAST COMMENT_BODY TRUE
J 2
(-2900 3550);
DISPLAY 0.872340 (-2900 3550);
PAINT GREEN (-2900 3550);
DISPLAY INVISIBLE (-2900 3550);
FORCEPROP 2 LAST PATH I142
J 0
(-2600 3725);
DISPLAY 0.680851 (-2600 3725);
DISPLAY INVISIBLE (-2600 3725);
FORCEADD OFFPAGE..1
R 2
(-2775 3550);
FORCEPROP 2 LAST $XR0 354 
J 0
(-2589 3550);
DISPLAY 0.638298 (-2589 3550);
PAINT MONO (-2589 3550);
FORCEPROP 2 LAST CDS_LIB standard
J 0
(-2775 3550);
DISPLAY INVISIBLE (-2775 3550);
FORCEPROP 1 LAST OFFPAGE TRUE
J 2
(-3100 3425);
DISPLAY 0.872340 (-3100 3425);
DISPLAY INVISIBLE (-3100 3425);
FORCEPROP 1 LAST COMMENT_BODY TRUE
J 2
(-2900 3450);
DISPLAY 0.872340 (-2900 3450);
PAINT GREEN (-2900 3450);
DISPLAY INVISIBLE (-2900 3450);
FORCEPROP 2 LAST PATH I143
J 0
(-2600 3625);
DISPLAY 0.680851 (-2600 3625);
DISPLAY INVISIBLE (-2600 3625);
FORCEADD OFFPAGE..1
R 2
(-2775 3450);
FORCEPROP 2 LAST $XR0 354 
J 0
(-2589 3450);
DISPLAY 0.638298 (-2589 3450);
PAINT MONO (-2589 3450);
FORCEPROP 2 LAST CDS_LIB standard
J 0
(-2775 3450);
DISPLAY INVISIBLE (-2775 3450);
FORCEPROP 1 LAST OFFPAGE TRUE
J 2
(-3100 3325);
DISPLAY 0.872340 (-3100 3325);
DISPLAY INVISIBLE (-3100 3325);
FORCEPROP 1 LAST COMMENT_BODY TRUE
J 2
(-2900 3350);
DISPLAY 0.872340 (-2900 3350);
PAINT GREEN (-2900 3350);
DISPLAY INVISIBLE (-2900 3350);
FORCEPROP 2 LAST PATH I144
J 0
(-2600 3525);
DISPLAY 0.680851 (-2600 3525);
DISPLAY INVISIBLE (-2600 3525);
FORCEADD OFFPAGE..1
R 2
(-2800 3350);
FORCEPROP 2 LAST $XR0 354 
J 0
(-2614 3350);
DISPLAY 0.638298 (-2614 3350);
PAINT MONO (-2614 3350);
FORCEPROP 2 LAST CDS_LIB standard
J 0
(-2800 3350);
DISPLAY INVISIBLE (-2800 3350);
FORCEPROP 1 LAST OFFPAGE TRUE
J 2
(-3125 3225);
DISPLAY 0.872340 (-3125 3225);
DISPLAY INVISIBLE (-3125 3225);
FORCEPROP 1 LAST COMMENT_BODY TRUE
J 2
(-2925 3250);
DISPLAY 0.872340 (-2925 3250);
PAINT GREEN (-2925 3250);
DISPLAY INVISIBLE (-2925 3250);
FORCEPROP 2 LAST PATH I145
J 0
(-2625 3425);
DISPLAY 0.680851 (-2625 3425);
DISPLAY INVISIBLE (-2625 3425);
FORCEADD Q_RES..1
(-6375 1650);
FORCEPROP 1 LAST LOCATION R695
J 0
(-6650 1650);
DISPLAY 0.787234 (-6650 1650);
FORCEPROP 2 LAST SEC 1
J 0
(-6425 1850);
DISPLAY 0.680851 (-6425 1850);
PAINT MONO (-6425 1850);
DISPLAY INVISIBLE (-6425 1850);
FORCEPROP 1 LASTPIN (-6475 1650) $PN 1
J 0
(-6463 1662);
DISPLAY 0.787234 (-6463 1662);
PAINT MONO (-6463 1662);
FORCEPROP 1 LASTPIN (-6275 1650) $PN 2
J 0
(-6313 1662);
DISPLAY 0.787234 (-6313 1662);
PAINT MONO (-6313 1662);
FORCEPROP 1 LAST TOLERANCE 1%
J 0
(-6500 1775);
DISPLAY 0.638298 (-6500 1775);
FORCEPROP 1 LAST VALUE 22
J 2
(-6550 1775);
DISPLAY 0.638298 (-6550 1775);
FORCEPROP 1 LAST WATTAGE 1/20W
J 2
(-6475 1725);
DISPLAY 0.638298 (-6475 1725);
FORCEPROP 1 LAST MATERIAL CHIP
J 0
(-6450 1725);
DISPLAY 0.638298 (-6450 1725);
FORCEPROP 1 LAST PACK_TYPE 0201LF
J 0
(-6300 1725);
DISPLAY 0.638298 (-6300 1725);
FORCEPROP 2 LAST CDS_LIB pure_quanta
J 0
(-6375 1650);
DISPLAY INVISIBLE (-6375 1650);
FORCEPROP 2 LAST SEC_TYPE 0201LF
J 0
(-6425 1850);
DISPLAY 0.680851 (-6425 1850);
DISPLAY INVISIBLE (-6425 1850);
FORCEPROP 1 LAST PATH I146
J 0
(-6425 1800);
DISPLAY 0.978723 (-6425 1800);
PAINT WHITE (-6425 1800);
DISPLAY INVISIBLE (-6425 1800);
FORCEPROP 1 LAST PART_NUMBER CS02201FE11
J 0
(-6425 1775);
DISPLAY 0.638298 (-6425 1775);
DISPLAY INVISIBLE (-6425 1775);
FORCEADD UNIVERSAL_GND..1
(-9025 3175);
FORCEPROP 3 LASTPIN (-9025 3225) SIG_NAME GND\g
J 0
(-9015 3235);
DISPLAY 0.659574 (-9015 3235);
PAINT MONO (-9015 3235);
DISPLAY INVISIBLE (-9015 3235);
FORCEPROP 2 LAST CDS_LIB pure_quanta_power
J 0
(-9025 3175);
DISPLAY INVISIBLE (-9025 3175);
FORCEPROP 1 LAST HDL_POWER GND
J 1
(-9000 3100);
DISPLAY 0.872340 (-9000 3100);
PAINT GREEN (-9000 3100);
DISPLAY INVISIBLE (-9000 3100);
FORCEPROP 1 LAST PATH I15
J 0
(-8950 3175);
DISPLAY 0.872340 (-8950 3175);
PAINT AQUA (-8950 3175);
DISPLAY INVISIBLE (-8950 3175);
FORCEADD Q_RES..2
(-9025 4125);
FORCEPROP 1 LAST LOCATION R909
J 0
(-8980 4250);
DISPLAY 0.787234 (-8980 4250);
FORCEPROP 0 LAST $SEC 1
J 0
(-8975 4300);
DISPLAY 0.680851 (-8975 4300);
PAINT MONO (-8975 4300);
DISPLAY INVISIBLE (-8975 4300);
FORCEPROP 0 LAST CDS_SEC 1
J 0
(-8975 4300);
DISPLAY 0.680851 (-8975 4300);
DISPLAY INVISIBLE (-8975 4300);
FORCEPROP 1 LASTPIN (-9025 4225) $PN 1
J 0
(-9020 4187);
DISPLAY 0.787234 (-9020 4187);
PAINT MONO (-9020 4187);
FORCEPROP 1 LASTPIN (-9025 4025) $PN 2
J 0
(-9020 4035);
DISPLAY 0.787234 (-9020 4035);
PAINT MONO (-9020 4035);
FORCEPROP 1 LAST VALUE 4.7K
J 0
(-8980 4200);
DISPLAY 0.787234 (-8980 4200);
FORCEPROP 1 LAST TOLERANCE 5%
J 0
(-8980 4150);
DISPLAY 0.787234 (-8980 4150);
FORCEPROP 1 LAST WATTAGE 1/20W
J 0
(-8985 4100);
DISPLAY 0.787234 (-8985 4100);
FORCEPROP 1 LAST MATERIAL EMPTY
J 0
(-8985 4050);
DISPLAY 0.787234 (-8985 4050);
FORCEPROP 1 LAST PACK_TYPE 0201LF
J 0
(-8975 3975);
DISPLAY 0.787234 (-8975 3975);
FORCEPROP 2 LAST CDS_LIB pure_quanta
J 0
(-9025 4125);
DISPLAY INVISIBLE (-9025 4125);
FORCEPROP 1 LAST PATH I17
J 0
(-8975 4300);
DISPLAY 0.978723 (-8975 4300);
PAINT WHITE (-8975 4300);
DISPLAY INVISIBLE (-8975 4300);
FORCEPROP 1 LAST PART_NUMBER CS24701JE04
J 0
(-8985 4000);
DISPLAY 0.978723 (-8985 4000);
DISPLAY INVISIBLE (-8985 4000);
FORCEADD P1V0..1
(-9025 4450);
FORCEPROP 3 LASTPIN (-9025 4400) SIG_NAME P1V8_CPU1_RT_1D\g
J 0
(-9015 4410);
DISPLAY 0.659574 (-9015 4410);
PAINT MONO (-9015 4410);
DISPLAY INVISIBLE (-9015 4410);
FORCEPROP 1 LAST HDL_POWER P1V8_CPU1_RT_1D
J 1
(-9025 4500);
DISPLAY 0.489362 (-9025 4500);
PAINT SKYBLUE (-9025 4500);
FORCEPROP 2 LAST CDS_LIB pure_quanta_power
J 0
(-9025 4450);
DISPLAY INVISIBLE (-9025 4450);
FORCEPROP 1 LAST PATH I18
J 0
(-8975 4475);
DISPLAY 0.872340 (-8975 4475);
PAINT AQUA (-8975 4475);
DISPLAY INVISIBLE (-8975 4475);
FORCEADD Q_RES..2
(-9000 5050);
FORCEPROP 1 LAST LOCATION R916
J 0
(-8955 5175);
DISPLAY 0.787234 (-8955 5175);
FORCEPROP 0 LAST $SEC 1
J 0
(-8950 5225);
DISPLAY 0.680851 (-8950 5225);
PAINT MONO (-8950 5225);
DISPLAY INVISIBLE (-8950 5225);
FORCEPROP 0 LAST CDS_SEC 1
J 0
(-8950 5225);
DISPLAY 0.680851 (-8950 5225);
DISPLAY INVISIBLE (-8950 5225);
FORCEPROP 1 LASTPIN (-9000 5150) $PN 1
J 0
(-8995 5112);
DISPLAY 0.787234 (-8995 5112);
PAINT MONO (-8995 5112);
FORCEPROP 1 LASTPIN (-9000 4950) $PN 2
J 0
(-8995 4960);
DISPLAY 0.787234 (-8995 4960);
PAINT MONO (-8995 4960);
FORCEPROP 1 LAST VALUE 10K
J 0
(-8955 5125);
DISPLAY 0.787234 (-8955 5125);
FORCEPROP 1 LAST TOLERANCE 1%
J 0
(-8955 5075);
DISPLAY 0.787234 (-8955 5075);
FORCEPROP 1 LAST WATTAGE 1/20W
J 0
(-8960 5025);
DISPLAY 0.787234 (-8960 5025);
FORCEPROP 1 LAST MATERIAL CHIP
J 0
(-8960 4975);
DISPLAY 0.787234 (-8960 4975);
FORCEPROP 1 LAST PACK_TYPE 0201LF
J 0
(-8960 4875);
DISPLAY 0.787234 (-8960 4875);
FORCEPROP 2 LAST CDS_LIB pure_quanta
J 0
(-9000 5050);
DISPLAY INVISIBLE (-9000 5050);
FORCEPROP 1 LAST PATH I19
J 0
(-8950 5225);
DISPLAY 0.978723 (-8950 5225);
PAINT WHITE (-8950 5225);
DISPLAY INVISIBLE (-8950 5225);
FORCEPROP 1 LAST PART_NUMBER CS31001FE17
J 0
(-8960 4925);
DISPLAY 0.638298 (-8960 4925);
DISPLAY INVISIBLE (-8960 4925);
FORCEADD Q_RES..2
(-8700 5050);
FORCEPROP 1 LAST LOCATION R917
J 0
(-8655 5175);
DISPLAY 0.787234 (-8655 5175);
FORCEPROP 0 LAST $SEC 1
J 0
(-8650 5225);
DISPLAY 0.680851 (-8650 5225);
PAINT MONO (-8650 5225);
DISPLAY INVISIBLE (-8650 5225);
FORCEPROP 0 LAST CDS_SEC 1
J 0
(-8650 5225);
DISPLAY 0.680851 (-8650 5225);
DISPLAY INVISIBLE (-8650 5225);
FORCEPROP 1 LASTPIN (-8700 5150) $PN 1
J 0
(-8695 5112);
DISPLAY 0.787234 (-8695 5112);
PAINT MONO (-8695 5112);
FORCEPROP 1 LASTPIN (-8700 4950) $PN 2
J 0
(-8695 4960);
DISPLAY 0.787234 (-8695 4960);
PAINT MONO (-8695 4960);
FORCEPROP 1 LAST WATTAGE 1/20W
J 0
(-8660 5025);
DISPLAY 0.787234 (-8660 5025);
FORCEPROP 1 LAST MATERIAL CHIP
J 0
(-8660 4975);
DISPLAY 0.787234 (-8660 4975);
FORCEPROP 1 LAST VALUE 10K
J 0
(-8655 5125);
DISPLAY 0.787234 (-8655 5125);
FORCEPROP 1 LAST TOLERANCE 1%
J 0
(-8655 5075);
DISPLAY 0.787234 (-8655 5075);
FORCEPROP 1 LAST PACK_TYPE 0201LF
J 0
(-8660 4875);
DISPLAY 0.787234 (-8660 4875);
FORCEPROP 2 LAST CDS_LIB pure_quanta
J 0
(-8700 5050);
DISPLAY INVISIBLE (-8700 5050);
FORCEPROP 1 LAST PATH I20
J 0
(-8650 5225);
DISPLAY 0.978723 (-8650 5225);
PAINT WHITE (-8650 5225);
DISPLAY INVISIBLE (-8650 5225);
FORCEPROP 1 LAST PART_NUMBER CS31001FE17
J 0
(-8660 4925);
DISPLAY 0.510638 (-8660 4925);
DISPLAY INVISIBLE (-8660 4925);
FORCEADD Q_RES..2
(-8375 5050);
FORCEPROP 1 LAST LOCATION R919
J 0
(-8330 5175);
DISPLAY 0.787234 (-8330 5175);
FORCEPROP 0 LAST $SEC 1
J 0
(-8325 5225);
DISPLAY 0.680851 (-8325 5225);
PAINT MONO (-8325 5225);
DISPLAY INVISIBLE (-8325 5225);
FORCEPROP 0 LAST CDS_SEC 1
J 0
(-8325 5225);
DISPLAY 0.680851 (-8325 5225);
DISPLAY INVISIBLE (-8325 5225);
FORCEPROP 1 LASTPIN (-8375 5150) $PN 1
J 0
(-8370 5112);
DISPLAY 0.787234 (-8370 5112);
PAINT MONO (-8370 5112);
FORCEPROP 1 LASTPIN (-8375 4950) $PN 2
J 0
(-8370 4960);
DISPLAY 0.787234 (-8370 4960);
PAINT MONO (-8370 4960);
FORCEPROP 1 LAST TOLERANCE 5%
J 0
(-8330 5075);
DISPLAY 0.787234 (-8330 5075);
FORCEPROP 1 LAST PACK_TYPE 0201LF
J 0
(-8335 4875);
DISPLAY 0.787234 (-8335 4875);
FORCEPROP 1 LAST MATERIAL CHIP
J 0
(-8335 4975);
DISPLAY 0.787234 (-8335 4975);
FORCEPROP 1 LAST WATTAGE 1/20W
J 0
(-8335 5025);
DISPLAY 0.787234 (-8335 5025);
FORCEPROP 1 LAST VALUE 4.7K
J 0
(-8330 5125);
DISPLAY 0.787234 (-8330 5125);
FORCEPROP 2 LAST CDS_LIB pure_quanta
J 0
(-8375 5050);
DISPLAY INVISIBLE (-8375 5050);
FORCEPROP 1 LAST PATH I21
J 0
(-8325 5225);
DISPLAY 0.978723 (-8325 5225);
PAINT WHITE (-8325 5225);
DISPLAY INVISIBLE (-8325 5225);
FORCEPROP 1 LAST PART_NUMBER CS24701JE04
J 0
(-8335 4925);
DISPLAY 0.978723 (-8335 4925);
DISPLAY INVISIBLE (-8335 4925);
FORCEADD Q_RES..2
(-9000 6000);
FORCEPROP 1 LAST LOCATION R915
J 0
(-8955 6125);
DISPLAY 0.787234 (-8955 6125);
FORCEPROP 0 LAST $SEC 1
J 0
(-8950 6175);
DISPLAY 0.680851 (-8950 6175);
PAINT MONO (-8950 6175);
DISPLAY INVISIBLE (-8950 6175);
FORCEPROP 0 LAST CDS_SEC 1
J 0
(-8950 6175);
DISPLAY 0.680851 (-8950 6175);
DISPLAY INVISIBLE (-8950 6175);
FORCEPROP 1 LASTPIN (-9000 6100) $PN 1
J 0
(-8995 6062);
DISPLAY 0.787234 (-8995 6062);
PAINT MONO (-8995 6062);
FORCEPROP 1 LASTPIN (-9000 5900) $PN 2
J 0
(-8995 5910);
DISPLAY 0.787234 (-8995 5910);
PAINT MONO (-8995 5910);
FORCEPROP 1 LAST TOLERANCE 5%
J 0
(-8955 6025);
DISPLAY 0.787234 (-8955 6025);
FORCEPROP 1 LAST PACK_TYPE 0201LF
J 0
(-8950 5850);
DISPLAY 0.787234 (-8950 5850);
FORCEPROP 1 LAST MATERIAL EMPTY
J 0
(-8960 5925);
DISPLAY 0.787234 (-8960 5925);
FORCEPROP 1 LAST WATTAGE 1/20W
J 0
(-8960 5975);
DISPLAY 0.787234 (-8960 5975);
FORCEPROP 1 LAST VALUE 4.7K
J 0
(-8955 6075);
DISPLAY 0.787234 (-8955 6075);
FORCEPROP 2 LAST CDS_LIB pure_quanta
J 0
(-9000 6000);
DISPLAY INVISIBLE (-9000 6000);
FORCEPROP 1 LAST PATH I22
J 0
(-8950 6175);
DISPLAY 0.978723 (-8950 6175);
PAINT WHITE (-8950 6175);
DISPLAY INVISIBLE (-8950 6175);
FORCEPROP 1 LAST PART_NUMBER CS24701JE04
J 0
(-8960 5875);
DISPLAY 0.978723 (-8960 5875);
DISPLAY INVISIBLE (-8960 5875);
FORCEADD Q_RES..2
(-8375 6000);
FORCEPROP 1 LAST LOCATION R918
J 0
(-8330 6125);
DISPLAY 0.787234 (-8330 6125);
FORCEPROP 0 LAST $SEC 1
J 0
(-8325 6175);
DISPLAY 0.680851 (-8325 6175);
PAINT MONO (-8325 6175);
DISPLAY INVISIBLE (-8325 6175);
FORCEPROP 0 LAST CDS_SEC 1
J 0
(-8325 6175);
DISPLAY 0.680851 (-8325 6175);
DISPLAY INVISIBLE (-8325 6175);
FORCEPROP 1 LASTPIN (-8375 6100) $PN 1
J 0
(-8370 6062);
DISPLAY 0.787234 (-8370 6062);
PAINT MONO (-8370 6062);
FORCEPROP 1 LASTPIN (-8375 5900) $PN 2
J 0
(-8370 5910);
DISPLAY 0.787234 (-8370 5910);
PAINT MONO (-8370 5910);
FORCEPROP 1 LAST TOLERANCE 5%
J 0
(-8330 6025);
DISPLAY 0.787234 (-8330 6025);
FORCEPROP 1 LAST PACK_TYPE 0201LF
J 0
(-8325 5850);
DISPLAY 0.787234 (-8325 5850);
FORCEPROP 1 LAST MATERIAL EMPTY
J 0
(-8335 5925);
DISPLAY 0.787234 (-8335 5925);
FORCEPROP 1 LAST WATTAGE 1/20W
J 0
(-8335 5975);
DISPLAY 0.787234 (-8335 5975);
FORCEPROP 1 LAST VALUE 4.7K
J 0
(-8330 6075);
DISPLAY 0.787234 (-8330 6075);
FORCEPROP 2 LAST CDS_LIB pure_quanta
J 0
(-8375 6000);
DISPLAY INVISIBLE (-8375 6000);
FORCEPROP 1 LAST PATH I23
J 0
(-8325 6175);
DISPLAY 0.978723 (-8325 6175);
PAINT WHITE (-8325 6175);
DISPLAY INVISIBLE (-8325 6175);
FORCEPROP 1 LAST PART_NUMBER CS24701JE04
J 0
(-8335 5875);
DISPLAY 0.978723 (-8335 5875);
DISPLAY INVISIBLE (-8335 5875);
FORCEADD P1V0..1
(-9000 6400);
FORCEPROP 3 LASTPIN (-9000 6350) SIG_NAME P1V8_CPU1_RT_1D\g
J 0
(-8990 6360);
DISPLAY 0.659574 (-8990 6360);
PAINT MONO (-8990 6360);
DISPLAY INVISIBLE (-8990 6360);
FORCEPROP 1 LAST HDL_POWER P1V8_CPU1_RT_1D
J 1
(-9000 6450);
DISPLAY 0.489362 (-9000 6450);
PAINT SKYBLUE (-9000 6450);
FORCEPROP 2 LAST CDS_LIB pure_quanta_power
J 0
(-9000 6400);
DISPLAY INVISIBLE (-9000 6400);
FORCEPROP 1 LAST PATH I24
J 0
(-8950 6425);
DISPLAY 0.872340 (-8950 6425);
PAINT AQUA (-8950 6425);
DISPLAY INVISIBLE (-8950 6425);
FORCEADD OFFPAGE..1
(-8100 1050);
FORCEPROP 2 LAST $XR0 183 
J 0
(-8352 1050);
DISPLAY 0.638298 (-8352 1050);
PAINT MONO (-8352 1050);
FORCEPROP 2 LAST CDS_LIB standard
J 0
(-8100 1050);
DISPLAY INVISIBLE (-8100 1050);
FORCEPROP 1 LAST OFFPAGE TRUE
J 0
(-7775 925);
DISPLAY 0.872340 (-7775 925);
DISPLAY INVISIBLE (-7775 925);
FORCEPROP 1 LAST COMMENT_BODY TRUE
J 0
(-7975 950);
DISPLAY 0.872340 (-7975 950);
PAINT GREEN (-7975 950);
DISPLAY INVISIBLE (-7975 950);
FORCEPROP 2 LAST PATH I25
J 0
(-8350 1100);
DISPLAY 0.680851 (-8350 1100);
DISPLAY INVISIBLE (-8350 1100);
FORCEADD OFFPAGE..1
(-8100 1200);
FORCEPROP 2 LAST $XR0 183 
J 0
(-8352 1200);
DISPLAY 0.638298 (-8352 1200);
PAINT MONO (-8352 1200);
FORCEPROP 2 LAST CDS_LIB standard
J 0
(-8100 1200);
DISPLAY INVISIBLE (-8100 1200);
FORCEPROP 1 LAST OFFPAGE TRUE
J 0
(-7775 1075);
DISPLAY 0.872340 (-7775 1075);
DISPLAY INVISIBLE (-7775 1075);
FORCEPROP 1 LAST COMMENT_BODY TRUE
J 0
(-7975 1100);
DISPLAY 0.872340 (-7975 1100);
PAINT GREEN (-7975 1100);
DISPLAY INVISIBLE (-7975 1100);
FORCEPROP 2 LAST PATH I26
J 0
(-8350 1250);
DISPLAY 0.680851 (-8350 1250);
DISPLAY INVISIBLE (-8350 1250);
FORCEADD OFFPAGE..3
R 2
(-7725 1550);
FORCEPROP 2 LAST $XR1 186 
J 0
(-8155 1550);
DISPLAY 0.638298 (-8155 1550);
PAINT MONO (-8155 1550);
FORCEPROP 2 LAST $XR0 185 
J 0
(-8035 1550);
DISPLAY 0.638298 (-8035 1550);
PAINT MONO (-8035 1550);
FORCEPROP 2 LAST CDS_LIB standard
J 0
(-7725 1550);
DISPLAY INVISIBLE (-7725 1550);
FORCEPROP 1 LAST OFFPAGE TRUE
J 2
(-8050 1425);
DISPLAY 0.872340 (-8050 1425);
PAINT GREEN (-8050 1425);
DISPLAY INVISIBLE (-8050 1425);
FORCEPROP 1 LAST COMMENT_BODY TRUE
J 2
(-7675 1450);
DISPLAY 0.872340 (-7675 1450);
PAINT GREEN (-7675 1450);
DISPLAY INVISIBLE (-7675 1450);
FORCEPROP 2 LAST PATH I27
J 0
(-8000 1600);
DISPLAY 0.680851 (-8000 1600);
DISPLAY INVISIBLE (-8000 1600);
FORCEADD OFFPAGE..5
(-7750 1650);
FORCEPROP 2 LAST $XR1 186 
J 0
(-8155 1650);
DISPLAY 0.638298 (-8155 1650);
PAINT MONO (-8155 1650);
FORCEPROP 2 LAST $XR0 185 
J 0
(-8035 1650);
DISPLAY 0.638298 (-8035 1650);
PAINT MONO (-8035 1650);
FORCEPROP 2 LAST CDS_LIB standard
J 0
(-7750 1650);
DISPLAY INVISIBLE (-7750 1650);
FORCEPROP 1 LAST OFFPAGE TRUE
J 0
(-7425 1525);
DISPLAY 0.872340 (-7425 1525);
PAINT GREEN (-7425 1525);
DISPLAY INVISIBLE (-7425 1525);
FORCEPROP 1 LAST COMMENT_BODY TRUE
J 0
(-7650 1575);
DISPLAY 0.872340 (-7650 1575);
PAINT GREEN (-7650 1575);
DISPLAY INVISIBLE (-7650 1575);
FORCEPROP 2 LAST PATH I28
J 0
(-8000 1700);
DISPLAY 0.680851 (-8000 1700);
DISPLAY INVISIBLE (-8000 1700);
FORCEADD UNIVERSAL_GND..1
(-6350 400);
FORCEPROP 3 LASTPIN (-6350 450) SIG_NAME GND\g
J 0
(-6340 460);
DISPLAY 0.659574 (-6340 460);
PAINT MONO (-6340 460);
DISPLAY INVISIBLE (-6340 460);
FORCEPROP 2 LAST CDS_LIB pure_quanta_power
J 0
(-6350 400);
DISPLAY INVISIBLE (-6350 400);
FORCEPROP 1 LAST HDL_POWER GND
J 1
(-6325 325);
DISPLAY 0.872340 (-6325 325);
PAINT GREEN (-6325 325);
DISPLAY INVISIBLE (-6325 325);
FORCEPROP 1 LAST PATH I29
J 0
(-6275 400);
DISPLAY 0.872340 (-6275 400);
PAINT AQUA (-6275 400);
DISPLAY INVISIBLE (-6275 400);
FORCEADD Q_RES..2
R 2
(-6350 725);
FORCEPROP 1 LAST LOCATION R641
J 2
(-6395 850);
DISPLAY 0.978723 (-6395 850);
PAINT SKYBLUE (-6395 850);
FORCEPROP 0 LAST $SEC 1
J 0
(-6375 900);
DISPLAY 0.680851 (-6375 900);
PAINT MONO (-6375 900);
DISPLAY INVISIBLE (-6375 900);
FORCEPROP 0 LAST CDS_SEC 1
J 0
(-6375 900);
DISPLAY 0.680851 (-6375 900);
DISPLAY INVISIBLE (-6375 900);
FORCEPROP 1 LASTPIN (-6350 825) $PN 1
J 2
(-6355 787);
DISPLAY 0.787234 (-6355 787);
PAINT MONO (-6355 787);
FORCEPROP 1 LASTPIN (-6350 625) $PN 2
J 2
(-6355 635);
DISPLAY 0.787234 (-6355 635);
PAINT MONO (-6355 635);
FORCEPROP 1 LAST WATTAGE 1/20W
J 2
(-6390 700);
DISPLAY 0.978723 (-6390 700);
FORCEPROP 1 LAST MATERIAL EMPTY
J 2
(-6390 650);
DISPLAY 0.978723 (-6390 650);
FORCEPROP 1 LAST PACK_TYPE 0201LF
J 2
(-6390 550);
DISPLAY 0.978723 (-6390 550);
FORCEPROP 1 LAST TOLERANCE 1%
J 2
(-6395 750);
DISPLAY 0.978723 (-6395 750);
FORCEPROP 1 LAST VALUE 51.1
J 2
(-6395 800);
DISPLAY 0.978723 (-6395 800);
FORCEPROP 2 LAST CDS_LIB pure_quanta
J 0
(-6350 725);
DISPLAY INVISIBLE (-6350 725);
FORCEPROP 1 LAST PATH I30
J 2
(-6400 900);
DISPLAY 0.978723 (-6400 900);
PAINT WHITE (-6400 900);
DISPLAY INVISIBLE (-6400 900);
FORCEPROP 1 LAST PART_NUMBER CS05111FE00
J 2
(-6390 600);
DISPLAY 0.978723 (-6390 600);
DISPLAY INVISIBLE (-6390 600);
FORCEADD Q_RES..1
(-6650 1050);
FORCEPROP 1 LAST LOCATION R622
J 0
(-6900 1050);
DISPLAY 0.978723 (-6900 1050);
PAINT SKYBLUE (-6900 1050);
FORCEPROP 2 LAST SEC 1
J 0
(-6700 1250);
DISPLAY 0.680851 (-6700 1250);
PAINT MONO (-6700 1250);
DISPLAY INVISIBLE (-6700 1250);
FORCEPROP 1 LASTPIN (-6750 1050) $PN 1
J 0
(-6738 1062);
DISPLAY 0.787234 (-6738 1062);
PAINT MONO (-6738 1062);
FORCEPROP 1 LASTPIN (-6550 1050) $PN 2
J 0
(-6588 1062);
DISPLAY 0.787234 (-6588 1062);
PAINT MONO (-6588 1062);
FORCEPROP 1 LAST PACK_TYPE 0201LF
J 0
(-6625 1125);
DISPLAY 0.787234 (-6625 1125);
FORCEPROP 1 LAST MATERIAL CHIP
J 0
(-6825 1125);
DISPLAY 0.787234 (-6825 1125);
FORCEPROP 2 LAST CDS_LIB pure_quanta
J 0
(-6650 1050);
DISPLAY INVISIBLE (-6650 1050);
FORCEPROP 1 LAST TOLERANCE 5%
J 0
(-6825 1175);
DISPLAY 0.787234 (-6825 1175);
DISPLAY INVISIBLE (-6825 1175);
FORCEPROP 1 LAST VALUE 0
J 2
(-6850 1175);
DISPLAY 0.787234 (-6850 1175);
DISPLAY INVISIBLE (-6850 1175);
FORCEPROP 1 LAST WATTAGE 1/20W
J 2
(-6850 1125);
DISPLAY 0.787234 (-6850 1125);
DISPLAY INVISIBLE (-6850 1125);
FORCEPROP 2 LAST SEC_TYPE 0201LF
J 0
(-6700 1250);
DISPLAY 0.680851 (-6700 1250);
DISPLAY INVISIBLE (-6700 1250);
FORCEPROP 1 LAST PATH I31
J 0
(-6700 1200);
DISPLAY 0.978723 (-6700 1200);
PAINT WHITE (-6700 1200);
DISPLAY INVISIBLE (-6700 1200);
FORCEPROP 1 LAST PART_NUMBER CS00001JE10
J 0
(-6700 1175);
DISPLAY 0.808511 (-6700 1175);
DISPLAY INVISIBLE (-6700 1175);
FORCEADD Q_RES..1
(-6650 1200);
FORCEPROP 1 LAST LOCATION R621
J 0
(-6900 1200);
DISPLAY 0.978723 (-6900 1200);
PAINT SKYBLUE (-6900 1200);
FORCEPROP 2 LAST SEC 1
J 0
(-6700 1400);
DISPLAY 0.680851 (-6700 1400);
PAINT MONO (-6700 1400);
DISPLAY INVISIBLE (-6700 1400);
FORCEPROP 1 LASTPIN (-6750 1200) $PN 1
J 0
(-6738 1212);
DISPLAY 0.787234 (-6738 1212);
PAINT MONO (-6738 1212);
FORCEPROP 1 LASTPIN (-6550 1200) $PN 2
J 0
(-6588 1212);
DISPLAY 0.787234 (-6588 1212);
PAINT MONO (-6588 1212);
FORCEPROP 1 LAST MATERIAL CHIP
J 0
(-6825 1275);
DISPLAY 0.787234 (-6825 1275);
FORCEPROP 1 LAST WATTAGE 1/20W
J 2
(-6850 1275);
DISPLAY 0.787234 (-6850 1275);
FORCEPROP 1 LAST PACK_TYPE 0201LF
J 0
(-6625 1275);
DISPLAY 0.787234 (-6625 1275);
FORCEPROP 1 LAST VALUE 0
J 2
(-6850 1325);
DISPLAY 0.787234 (-6850 1325);
FORCEPROP 1 LAST TOLERANCE 5%
J 0
(-6825 1325);
DISPLAY 0.787234 (-6825 1325);
FORCEPROP 2 LAST CDS_LIB pure_quanta
J 0
(-6650 1200);
DISPLAY INVISIBLE (-6650 1200);
FORCEPROP 0 LAST SEC_TYPE 0201LF
J 0
(-6700 1400);
DISPLAY 0.680851 (-6700 1400);
DISPLAY INVISIBLE (-6700 1400);
FORCEPROP 1 LAST PATH I32
J 0
(-6700 1350);
DISPLAY 0.978723 (-6700 1350);
PAINT WHITE (-6700 1350);
DISPLAY INVISIBLE (-6700 1350);
FORCEPROP 1 LAST PART_NUMBER CS00001JE10
J 0
(-6700 1325);
DISPLAY 0.808511 (-6700 1325);
DISPLAY INVISIBLE (-6700 1325);
FORCEADD Q_RES..1
(-6375 1550);
FORCEPROP 1 LAST LOCATION R696
J 0
(-6625 1575);
DISPLAY 0.978723 (-6625 1575);
PAINT SKYBLUE (-6625 1575);
FORCEPROP 0 LAST $SEC 1
J 0
(-6525 1625);
DISPLAY 0.680851 (-6525 1625);
PAINT MONO (-6525 1625);
DISPLAY INVISIBLE (-6525 1625);
FORCEPROP 0 LAST CDS_SEC 1
J 0
(-6525 1625);
DISPLAY 0.680851 (-6525 1625);
DISPLAY INVISIBLE (-6525 1625);
FORCEPROP 1 LASTPIN (-6475 1550) $PN 1
J 0
(-6463 1562);
DISPLAY 0.787234 (-6463 1562);
PAINT MONO (-6463 1562);
FORCEPROP 1 LASTPIN (-6275 1550) $PN 2
J 0
(-6313 1562);
DISPLAY 0.787234 (-6313 1562);
PAINT MONO (-6313 1562);
FORCEPROP 1 LAST VALUE 49.9
J 2
(-6475 1450);
DISPLAY 0.638298 (-6475 1450);
FORCEPROP 1 LAST WATTAGE 1/20W
J 2
(-6275 1450);
DISPLAY 0.638298 (-6275 1450);
FORCEPROP 1 LAST TOLERANCE 1%
J 0
(-6200 1450);
DISPLAY 0.638298 (-6200 1450);
FORCEPROP 1 LAST PACK_TYPE 0201LF
J 0
(-6150 1500);
DISPLAY 0.638298 (-6150 1500);
FORCEPROP 1 LAST MATERIAL CHIP
J 0
(-6675 1500);
DISPLAY 0.638298 (-6675 1500);
FORCEPROP 2 LAST CDS_LIB pure_quanta
J 0
(-6375 1550);
DISPLAY INVISIBLE (-6375 1550);
FORCEPROP 1 LAST PATH I33
J 0
(-6425 1700);
DISPLAY 0.978723 (-6425 1700);
PAINT WHITE (-6425 1700);
DISPLAY INVISIBLE (-6425 1700);
FORCEPROP 1 LAST PART_NUMBER CS04991FE06
J 0
(-6525 1500);
DISPLAY 0.638298 (-6525 1500);
DISPLAY INVISIBLE (-6525 1500);
FORCEADD OFFPAGE..1
(-6200 1950);
FORCEPROP 2 LAST $XR0 354 
J 0
(-6452 1950);
DISPLAY 0.638298 (-6452 1950);
PAINT MONO (-6452 1950);
FORCEPROP 2 LAST CDS_LIB standard
J 0
(-6200 1950);
DISPLAY INVISIBLE (-6200 1950);
FORCEPROP 1 LAST OFFPAGE TRUE
J 0
(-5875 1825);
DISPLAY 0.872340 (-5875 1825);
DISPLAY INVISIBLE (-5875 1825);
FORCEPROP 1 LAST COMMENT_BODY TRUE
J 0
(-6075 1850);
DISPLAY 0.872340 (-6075 1850);
PAINT GREEN (-6075 1850);
DISPLAY INVISIBLE (-6075 1850);
FORCEPROP 2 LAST PATH I35
J 0
(-6475 2000);
DISPLAY 0.680851 (-6475 2000);
DISPLAY INVISIBLE (-6475 2000);
FORCEADD OFFPAGE..1
(-6200 2050);
FORCEPROP 2 LAST $XR0 354 
J 0
(-6452 2050);
DISPLAY 0.638298 (-6452 2050);
PAINT MONO (-6452 2050);
FORCEPROP 2 LAST CDS_LIB standard
J 0
(-6200 2050);
DISPLAY INVISIBLE (-6200 2050);
FORCEPROP 1 LAST OFFPAGE TRUE
J 0
(-5875 1925);
DISPLAY 0.872340 (-5875 1925);
DISPLAY INVISIBLE (-5875 1925);
FORCEPROP 1 LAST COMMENT_BODY TRUE
J 0
(-6075 1950);
DISPLAY 0.872340 (-6075 1950);
PAINT GREEN (-6075 1950);
DISPLAY INVISIBLE (-6075 1950);
FORCEPROP 2 LAST PATH I36
J 0
(-6475 2100);
DISPLAY 0.680851 (-6475 2100);
DISPLAY INVISIBLE (-6475 2100);
FORCEADD OFFPAGE..1
(-7700 2900);
FORCEPROP 2 LAST $XR0 184 
J 0
(-7982 2900);
DISPLAY 0.638298 (-7982 2900);
PAINT MONO (-7982 2900);
FORCEPROP 2 LAST CDS_LIB standard
J 0
(-7700 2900);
DISPLAY INVISIBLE (-7700 2900);
FORCEPROP 1 LAST OFFPAGE TRUE
J 0
(-7375 2775);
DISPLAY 0.872340 (-7375 2775);
DISPLAY INVISIBLE (-7375 2775);
FORCEPROP 1 LAST COMMENT_BODY TRUE
J 0
(-7575 2800);
DISPLAY 0.872340 (-7575 2800);
PAINT GREEN (-7575 2800);
DISPLAY INVISIBLE (-7575 2800);
FORCEPROP 2 LAST PATH I37
J 0
(-7950 2950);
DISPLAY 0.680851 (-7950 2950);
DISPLAY INVISIBLE (-7950 2950);
FORCEADD OFFPAGE..3
R 2
(-7700 2800);
FORCEPROP 2 LAST $XR0 184 
J 0
(-8010 2800);
DISPLAY 0.638298 (-8010 2800);
PAINT MONO (-8010 2800);
FORCEPROP 2 LAST CDS_LIB standard
J 0
(-7700 2800);
DISPLAY INVISIBLE (-7700 2800);
FORCEPROP 1 LAST OFFPAGE TRUE
J 2
(-8025 2675);
DISPLAY 0.872340 (-8025 2675);
PAINT GREEN (-8025 2675);
DISPLAY INVISIBLE (-8025 2675);
FORCEPROP 1 LAST COMMENT_BODY TRUE
J 2
(-7650 2700);
DISPLAY 0.872340 (-7650 2700);
PAINT GREEN (-7650 2700);
DISPLAY INVISIBLE (-7650 2700);
FORCEPROP 2 LAST PATH I38
J 0
(-8000 2850);
DISPLAY 0.680851 (-8000 2850);
DISPLAY INVISIBLE (-8000 2850);
FORCEADD OFFPAGE..5
R 2
(-7850 3900);
FORCEPROP 2 LAST $XR0 354 
J 0
(-7661 3900);
DISPLAY 0.638298 (-7661 3900);
PAINT MONO (-7661 3900);
FORCEPROP 2 LAST CDS_LIB standard
J 0
(-7850 3900);
DISPLAY INVISIBLE (-7850 3900);
FORCEPROP 1 LAST OFFPAGE TRUE
J 2
(-8175 3775);
DISPLAY 0.872340 (-8175 3775);
PAINT GREEN (-8175 3775);
DISPLAY INVISIBLE (-8175 3775);
FORCEPROP 1 LAST COMMENT_BODY TRUE
J 2
(-7950 3825);
DISPLAY 0.872340 (-7950 3825);
PAINT GREEN (-7950 3825);
DISPLAY INVISIBLE (-7950 3825);
FORCEPROP 2 LAST PATH I39
J 0
(-7650 3950);
DISPLAY 0.680851 (-7650 3950);
DISPLAY INVISIBLE (-7650 3950);
FORCEADD OFFPAGE..1
(-6200 2150);
FORCEPROP 2 LAST $XR0 354 
J 0
(-6452 2150);
DISPLAY 0.638298 (-6452 2150);
PAINT MONO (-6452 2150);
FORCEPROP 2 LAST CDS_LIB standard
J 0
(-6200 2150);
DISPLAY INVISIBLE (-6200 2150);
FORCEPROP 1 LAST OFFPAGE TRUE
J 0
(-5875 2025);
DISPLAY 0.872340 (-5875 2025);
DISPLAY INVISIBLE (-5875 2025);
FORCEPROP 1 LAST COMMENT_BODY TRUE
J 0
(-6075 2050);
DISPLAY 0.872340 (-6075 2050);
PAINT GREEN (-6075 2050);
DISPLAY INVISIBLE (-6075 2050);
FORCEPROP 2 LAST PATH I40
J 0
(-6475 2200);
DISPLAY 0.680851 (-6475 2200);
DISPLAY INVISIBLE (-6475 2200);
FORCEADD Q_RES..1
(-6400 2800);
FORCEPROP 1 LAST LOCATION R914
J 0
(-6650 2825);
DISPLAY 0.978723 (-6650 2825);
FORCEPROP 0 LAST $SEC 1
J 0
(-6650 2875);
DISPLAY 0.680851 (-6650 2875);
PAINT MONO (-6650 2875);
DISPLAY INVISIBLE (-6650 2875);
FORCEPROP 0 LAST CDS_SEC 1
J 0
(-6650 2875);
DISPLAY 0.680851 (-6650 2875);
DISPLAY INVISIBLE (-6650 2875);
FORCEPROP 1 LASTPIN (-6500 2800) $PN 1
J 0
(-6488 2812);
DISPLAY 0.787234 (-6488 2812);
PAINT MONO (-6488 2812);
FORCEPROP 1 LASTPIN (-6300 2800) $PN 2
J 0
(-6338 2812);
DISPLAY 0.787234 (-6338 2812);
PAINT MONO (-6338 2812);
FORCEPROP 1 LAST WATTAGE 1/20W
J 2
(-6600 2875);
DISPLAY 0.787234 (-6600 2875);
DISPLAY INVISIBLE (-6600 2875);
FORCEPROP 1 LAST VALUE 0
J 2
(-6600 2925);
DISPLAY 0.787234 (-6600 2925);
DISPLAY INVISIBLE (-6600 2925);
FORCEPROP 1 LAST TOLERANCE 5%
J 0
(-6575 2925);
DISPLAY 0.787234 (-6575 2925);
DISPLAY INVISIBLE (-6575 2925);
FORCEPROP 1 LAST MATERIAL CHIP
J 0
(-6575 2875);
DISPLAY 0.787234 (-6575 2875);
DISPLAY INVISIBLE (-6575 2875);
FORCEPROP 1 LAST PACK_TYPE 0201LF
J 0
(-6375 2875);
DISPLAY 0.787234 (-6375 2875);
DISPLAY INVISIBLE (-6375 2875);
FORCEPROP 2 LAST CDS_LIB pure_quanta
J 0
(-6400 2800);
DISPLAY INVISIBLE (-6400 2800);
FORCEPROP 1 LAST PATH I41
J 0
(-6450 2950);
DISPLAY 0.978723 (-6450 2950);
PAINT WHITE (-6450 2950);
DISPLAY INVISIBLE (-6450 2950);
FORCEPROP 1 LAST PART_NUMBER CS00001JE10
J 0
(-6450 2925);
DISPLAY 0.808511 (-6450 2925);
DISPLAY INVISIBLE (-6450 2925);
FORCEADD Q_RES..1
(-6400 2900);
FORCEPROP 1 LAST LOCATION R913
J 0
(-6650 2925);
DISPLAY 0.978723 (-6650 2925);
FORCEPROP 0 LAST $SEC 1
J 0
(-6450 3075);
DISPLAY 0.680851 (-6450 3075);
PAINT MONO (-6450 3075);
DISPLAY INVISIBLE (-6450 3075);
FORCEPROP 0 LAST CDS_SEC 1
J 0
(-6450 3075);
DISPLAY 0.680851 (-6450 3075);
DISPLAY INVISIBLE (-6450 3075);
FORCEPROP 1 LASTPIN (-6500 2900) $PN 1
J 0
(-6488 2912);
DISPLAY 0.787234 (-6488 2912);
PAINT MONO (-6488 2912);
FORCEPROP 1 LASTPIN (-6300 2900) $PN 2
J 0
(-6338 2912);
DISPLAY 0.787234 (-6338 2912);
PAINT MONO (-6338 2912);
FORCEPROP 1 LAST VALUE 0
J 2
(-6600 3025);
DISPLAY 0.787234 (-6600 3025);
FORCEPROP 1 LAST PACK_TYPE 0201LF
J 0
(-6375 2975);
DISPLAY 0.787234 (-6375 2975);
FORCEPROP 1 LAST MATERIAL CHIP
J 0
(-6575 2975);
DISPLAY 0.787234 (-6575 2975);
FORCEPROP 1 LAST WATTAGE 1/20W
J 2
(-6600 2975);
DISPLAY 0.787234 (-6600 2975);
FORCEPROP 1 LAST TOLERANCE 5%
J 0
(-6575 3025);
DISPLAY 0.787234 (-6575 3025);
FORCEPROP 2 LAST CDS_LIB pure_quanta
J 0
(-6400 2900);
DISPLAY INVISIBLE (-6400 2900);
FORCEPROP 1 LAST PATH I42
J 0
(-6450 3050);
DISPLAY 0.978723 (-6450 3050);
PAINT WHITE (-6450 3050);
DISPLAY INVISIBLE (-6450 3050);
FORCEPROP 1 LAST PART_NUMBER CS00001JE10
J 0
(-6450 3025);
DISPLAY 0.808511 (-6450 3025);
DISPLAY INVISIBLE (-6450 3025);
FORCEADD OFFPAGE..1
(-6075 3350);
FORCEPROP 2 LAST $XR0 354 
J 0
(-6327 3350);
DISPLAY 0.638298 (-6327 3350);
PAINT MONO (-6327 3350);
FORCEPROP 2 LAST CDS_LIB standard
J 0
(-6075 3350);
DISPLAY INVISIBLE (-6075 3350);
FORCEPROP 1 LAST OFFPAGE TRUE
J 0
(-5750 3225);
DISPLAY 0.872340 (-5750 3225);
DISPLAY INVISIBLE (-5750 3225);
FORCEPROP 1 LAST COMMENT_BODY TRUE
J 0
(-5950 3250);
DISPLAY 0.872340 (-5950 3250);
PAINT GREEN (-5950 3250);
DISPLAY INVISIBLE (-5950 3250);
FORCEPROP 2 LAST PATH I43
J 0
(-6325 3400);
DISPLAY 0.680851 (-6325 3400);
DISPLAY INVISIBLE (-6325 3400);
FORCEADD OFFPAGE..1
(-6075 3250);
FORCEPROP 2 LAST $XR0 354 
J 0
(-6327 3250);
DISPLAY 0.638298 (-6327 3250);
PAINT MONO (-6327 3250);
FORCEPROP 2 LAST CDS_LIB standard
J 0
(-6075 3250);
DISPLAY INVISIBLE (-6075 3250);
FORCEPROP 1 LAST OFFPAGE TRUE
J 0
(-5750 3125);
DISPLAY 0.872340 (-5750 3125);
DISPLAY INVISIBLE (-5750 3125);
FORCEPROP 1 LAST COMMENT_BODY TRUE
J 0
(-5950 3150);
DISPLAY 0.872340 (-5950 3150);
PAINT GREEN (-5950 3150);
DISPLAY INVISIBLE (-5950 3150);
FORCEPROP 2 LAST PATH I44
J 0
(-6325 3300);
DISPLAY 0.680851 (-6325 3300);
DISPLAY INVISIBLE (-6325 3300);
FORCEADD UNIVERSAL_GND..1
(-6200 400);
FORCEPROP 3 LASTPIN (-6200 450) SIG_NAME GND\g
J 0
(-6190 460);
DISPLAY 0.659574 (-6190 460);
PAINT MONO (-6190 460);
DISPLAY INVISIBLE (-6190 460);
FORCEPROP 2 LAST CDS_LIB pure_quanta_power
J 0
(-6200 400);
DISPLAY INVISIBLE (-6200 400);
FORCEPROP 1 LAST HDL_POWER GND
J 1
(-6175 325);
DISPLAY 0.872340 (-6175 325);
PAINT GREEN (-6175 325);
DISPLAY INVISIBLE (-6175 325);
FORCEPROP 1 LAST PATH I45
J 0
(-6125 400);
DISPLAY 0.872340 (-6125 400);
PAINT AQUA (-6125 400);
DISPLAY INVISIBLE (-6125 400);
FORCEADD Q_RES..2
(-6200 725);
FORCEPROP 1 LAST LOCATION R642
J 0
(-6155 850);
DISPLAY 0.978723 (-6155 850);
PAINT SKYBLUE (-6155 850);
FORCEPROP 0 LAST $SEC 1
J 0
(-6150 900);
DISPLAY 0.680851 (-6150 900);
PAINT MONO (-6150 900);
DISPLAY INVISIBLE (-6150 900);
FORCEPROP 0 LAST CDS_SEC 1
J 0
(-6150 900);
DISPLAY 0.680851 (-6150 900);
DISPLAY INVISIBLE (-6150 900);
FORCEPROP 1 LASTPIN (-6200 825) $PN 1
J 0
(-6195 787);
DISPLAY 0.787234 (-6195 787);
PAINT MONO (-6195 787);
FORCEPROP 1 LASTPIN (-6200 625) $PN 2
J 0
(-6195 635);
DISPLAY 0.787234 (-6195 635);
PAINT MONO (-6195 635);
FORCEPROP 1 LAST VALUE 51.1
J 0
(-6155 800);
DISPLAY 0.978723 (-6155 800);
FORCEPROP 1 LAST PACK_TYPE 0201LF
J 0
(-6160 550);
DISPLAY 0.978723 (-6160 550);
FORCEPROP 1 LAST MATERIAL EMPTY
J 0
(-6160 650);
DISPLAY 0.978723 (-6160 650);
FORCEPROP 1 LAST WATTAGE 1/20W
J 0
(-6160 700);
DISPLAY 0.978723 (-6160 700);
FORCEPROP 1 LAST TOLERANCE 1%
J 0
(-6155 750);
DISPLAY 0.978723 (-6155 750);
FORCEPROP 2 LAST CDS_LIB pure_quanta
J 0
(-6200 725);
DISPLAY INVISIBLE (-6200 725);
FORCEPROP 1 LAST PATH I46
J 0
(-6150 900);
DISPLAY 0.978723 (-6150 900);
PAINT WHITE (-6150 900);
DISPLAY INVISIBLE (-6150 900);
FORCEPROP 1 LAST PART_NUMBER CS05111FE00
J 0
(-6160 600);
DISPLAY 0.978723 (-6160 600);
DISPLAY INVISIBLE (-6160 600);
FORCEADD OFFPAGE..1
(-6025 2450);
FORCEPROP 2 LAST $XR0 354 
J 0
(-6307 2450);
DISPLAY 0.638298 (-6307 2450);
PAINT MONO (-6307 2450);
FORCEPROP 2 LAST CDS_LIB standard
J 0
(-6025 2450);
DISPLAY INVISIBLE (-6025 2450);
FORCEPROP 1 LAST OFFPAGE TRUE
J 0
(-5700 2325);
DISPLAY 0.872340 (-5700 2325);
DISPLAY INVISIBLE (-5700 2325);
FORCEPROP 1 LAST COMMENT_BODY TRUE
J 0
(-5900 2350);
DISPLAY 0.872340 (-5900 2350);
PAINT GREEN (-5900 2350);
DISPLAY INVISIBLE (-5900 2350);
FORCEPROP 2 LAST PATH I47
J 0
(-6275 2500);
DISPLAY 0.680851 (-6275 2500);
DISPLAY INVISIBLE (-6275 2500);
FORCEADD OFFPAGE..1
(-6025 2550);
FORCEPROP 2 LAST $XR0 354 
J 0
(-6307 2550);
DISPLAY 0.638298 (-6307 2550);
PAINT MONO (-6307 2550);
FORCEPROP 2 LAST CDS_LIB standard
J 0
(-6025 2550);
DISPLAY INVISIBLE (-6025 2550);
FORCEPROP 1 LAST OFFPAGE TRUE
J 0
(-5700 2425);
DISPLAY 0.872340 (-5700 2425);
DISPLAY INVISIBLE (-5700 2425);
FORCEPROP 1 LAST COMMENT_BODY TRUE
J 0
(-5900 2450);
DISPLAY 0.872340 (-5900 2450);
PAINT GREEN (-5900 2450);
DISPLAY INVISIBLE (-5900 2450);
FORCEPROP 2 LAST PATH I48
J 0
(-6275 2600);
DISPLAY 0.680851 (-6275 2600);
DISPLAY INVISIBLE (-6275 2600);
FORCEADD OFFPAGE..1
(-6025 2650);
FORCEPROP 2 LAST $XR0 354 
J 0
(-6307 2650);
DISPLAY 0.638298 (-6307 2650);
PAINT MONO (-6307 2650);
FORCEPROP 2 LAST CDS_LIB standard
J 0
(-6025 2650);
DISPLAY INVISIBLE (-6025 2650);
FORCEPROP 1 LAST OFFPAGE TRUE
J 0
(-5700 2525);
DISPLAY 0.872340 (-5700 2525);
DISPLAY INVISIBLE (-5700 2525);
FORCEPROP 1 LAST COMMENT_BODY TRUE
J 0
(-5900 2550);
DISPLAY 0.872340 (-5900 2550);
PAINT GREEN (-5900 2550);
DISPLAY INVISIBLE (-5900 2550);
FORCEPROP 2 LAST PATH I49
J 0
(-6275 2700);
DISPLAY 0.680851 (-6275 2700);
DISPLAY INVISIBLE (-6275 2700);
FORCEADD Q_RES..2
(-8075 5025);
FORCEPROP 1 LAST LOCATION R921
J 0
(-8030 5150);
DISPLAY 0.787234 (-8030 5150);
FORCEPROP 0 LAST $SEC 1
J 0
(-8025 5200);
DISPLAY 0.680851 (-8025 5200);
PAINT MONO (-8025 5200);
DISPLAY INVISIBLE (-8025 5200);
FORCEPROP 0 LAST CDS_SEC 1
J 0
(-8025 5200);
DISPLAY 0.680851 (-8025 5200);
DISPLAY INVISIBLE (-8025 5200);
FORCEPROP 1 LASTPIN (-8075 5125) $PN 1
J 0
(-8070 5087);
DISPLAY 0.787234 (-8070 5087);
PAINT MONO (-8070 5087);
FORCEPROP 1 LASTPIN (-8075 4925) $PN 2
J 0
(-8070 4935);
DISPLAY 0.787234 (-8070 4935);
PAINT MONO (-8070 4935);
FORCEPROP 1 LAST VALUE 4.7K
J 0
(-8030 5100);
DISPLAY 0.787234 (-8030 5100);
FORCEPROP 1 LAST PACK_TYPE 0201LF
J 0
(-8035 4850);
DISPLAY 0.787234 (-8035 4850);
FORCEPROP 1 LAST TOLERANCE 5%
J 0
(-8030 5050);
DISPLAY 0.787234 (-8030 5050);
FORCEPROP 1 LAST WATTAGE 1/20W
J 0
(-8035 5000);
DISPLAY 0.787234 (-8035 5000);
FORCEPROP 1 LAST MATERIAL CHIP
J 0
(-8035 4950);
DISPLAY 0.787234 (-8035 4950);
FORCEPROP 2 LAST CDS_LIB pure_quanta
J 0
(-8075 5025);
DISPLAY INVISIBLE (-8075 5025);
FORCEPROP 1 LAST PATH I50
J 0
(-8025 5200);
DISPLAY 0.978723 (-8025 5200);
PAINT WHITE (-8025 5200);
DISPLAY INVISIBLE (-8025 5200);
FORCEPROP 1 LAST PART_NUMBER CS24701JE04
J 0
(-8035 4900);
DISPLAY 0.978723 (-8035 4900);
DISPLAY INVISIBLE (-8035 4900);
FORCEADD Q_RES..2
(-7775 5025);
FORCEPROP 1 LAST LOCATION R923
J 0
(-7730 5150);
DISPLAY 0.787234 (-7730 5150);
FORCEPROP 0 LAST $SEC 1
J 0
(-7725 5200);
DISPLAY 0.680851 (-7725 5200);
PAINT MONO (-7725 5200);
DISPLAY INVISIBLE (-7725 5200);
FORCEPROP 0 LAST CDS_SEC 1
J 0
(-7725 5200);
DISPLAY 0.680851 (-7725 5200);
DISPLAY INVISIBLE (-7725 5200);
FORCEPROP 1 LASTPIN (-7775 5125) $PN 1
J 0
(-7770 5087);
DISPLAY 0.787234 (-7770 5087);
PAINT MONO (-7770 5087);
FORCEPROP 1 LASTPIN (-7775 4925) $PN 2
J 0
(-7770 4935);
DISPLAY 0.787234 (-7770 4935);
PAINT MONO (-7770 4935);
FORCEPROP 1 LAST WATTAGE 1/20W
J 0
(-7735 5000);
DISPLAY 0.787234 (-7735 5000);
FORCEPROP 1 LAST MATERIAL CHIP
J 0
(-7735 4950);
DISPLAY 0.787234 (-7735 4950);
FORCEPROP 1 LAST PACK_TYPE 0201LF
J 0
(-7735 4850);
DISPLAY 0.787234 (-7735 4850);
FORCEPROP 1 LAST VALUE 4.7K
J 0
(-7730 5100);
DISPLAY 0.787234 (-7730 5100);
FORCEPROP 1 LAST TOLERANCE 5%
J 0
(-7730 5050);
DISPLAY 0.787234 (-7730 5050);
FORCEPROP 2 LAST CDS_LIB pure_quanta
J 0
(-7775 5025);
DISPLAY INVISIBLE (-7775 5025);
FORCEPROP 1 LAST PATH I51
J 0
(-7725 5200);
DISPLAY 0.978723 (-7725 5200);
PAINT WHITE (-7725 5200);
DISPLAY INVISIBLE (-7725 5200);
FORCEPROP 1 LAST PART_NUMBER CS24701JE04
J 0
(-7735 4900);
DISPLAY 0.787234 (-7735 4900);
DISPLAY INVISIBLE (-7735 4900);
FORCEADD UNIVERSAL_GND..1
(-7475 4550);
FORCEPROP 3 LASTPIN (-7475 4600) SIG_NAME GND\g
J 0
(-7465 4610);
DISPLAY 0.659574 (-7465 4610);
PAINT MONO (-7465 4610);
DISPLAY INVISIBLE (-7465 4610);
FORCEPROP 2 LAST CDS_LIB pure_quanta_power
J 0
(-7475 4550);
DISPLAY INVISIBLE (-7475 4550);
FORCEPROP 1 LAST HDL_POWER GND
J 1
(-7450 4475);
DISPLAY 0.872340 (-7450 4475);
PAINT GREEN (-7450 4475);
DISPLAY INVISIBLE (-7450 4475);
FORCEPROP 1 LAST PATH I52
J 0
(-7400 4550);
DISPLAY 0.872340 (-7400 4550);
PAINT AQUA (-7400 4550);
DISPLAY INVISIBLE (-7400 4550);
FORCEADD Q_RES..2
(-7475 5000);
FORCEPROP 1 LAST LOCATION R924
J 0
(-7430 5125);
DISPLAY 0.787234 (-7430 5125);
FORCEPROP 0 LAST $SEC 1
J 0
(-7425 5175);
DISPLAY 0.680851 (-7425 5175);
PAINT MONO (-7425 5175);
DISPLAY INVISIBLE (-7425 5175);
FORCEPROP 0 LAST CDS_SEC 1
J 0
(-7425 5175);
DISPLAY 0.680851 (-7425 5175);
DISPLAY INVISIBLE (-7425 5175);
FORCEPROP 1 LASTPIN (-7475 5100) $PN 1
J 0
(-7470 5062);
DISPLAY 0.787234 (-7470 5062);
PAINT MONO (-7470 5062);
FORCEPROP 1 LASTPIN (-7475 4900) $PN 2
J 0
(-7470 4910);
DISPLAY 0.787234 (-7470 4910);
PAINT MONO (-7470 4910);
FORCEPROP 1 LAST WATTAGE 1/20W
J 0
(-7435 4975);
DISPLAY 0.787234 (-7435 4975);
FORCEPROP 1 LAST VALUE 4.7K
J 0
(-7430 5075);
DISPLAY 0.787234 (-7430 5075);
FORCEPROP 1 LAST PACK_TYPE 0201LF
J 0
(-7435 4825);
DISPLAY 0.787234 (-7435 4825);
FORCEPROP 1 LAST MATERIAL CHIP
J 0
(-7435 4925);
DISPLAY 0.787234 (-7435 4925);
FORCEPROP 1 LAST TOLERANCE 5%
J 0
(-7430 5025);
DISPLAY 0.787234 (-7430 5025);
FORCEPROP 2 LAST CDS_LIB pure_quanta
J 0
(-7475 5000);
DISPLAY INVISIBLE (-7475 5000);
FORCEPROP 1 LAST PATH I53
J 0
(-7425 5175);
DISPLAY 0.978723 (-7425 5175);
PAINT WHITE (-7425 5175);
DISPLAY INVISIBLE (-7425 5175);
FORCEPROP 1 LAST PART_NUMBER CS24701JE04
J 0
(-7435 4875);
DISPLAY 0.638298 (-7435 4875);
DISPLAY INVISIBLE (-7435 4875);
FORCEADD Q_RES..2
(-8075 5950);
FORCEPROP 1 LAST LOCATION R920
J 0
(-8030 6075);
DISPLAY 0.787234 (-8030 6075);
FORCEPROP 0 LAST $SEC 1
J 0
(-8025 6125);
DISPLAY 0.680851 (-8025 6125);
PAINT MONO (-8025 6125);
DISPLAY INVISIBLE (-8025 6125);
FORCEPROP 0 LAST CDS_SEC 1
J 0
(-8025 6125);
DISPLAY 0.680851 (-8025 6125);
DISPLAY INVISIBLE (-8025 6125);
FORCEPROP 1 LASTPIN (-8075 6050) $PN 1
J 0
(-8070 6012);
DISPLAY 0.787234 (-8070 6012);
PAINT MONO (-8070 6012);
FORCEPROP 1 LASTPIN (-8075 5850) $PN 2
J 0
(-8070 5860);
DISPLAY 0.787234 (-8070 5860);
PAINT MONO (-8070 5860);
FORCEPROP 1 LAST MATERIAL EMPTY
J 0
(-8035 5875);
DISPLAY 0.787234 (-8035 5875);
FORCEPROP 1 LAST PACK_TYPE 0201LF
J 0
(-8025 5800);
DISPLAY 0.787234 (-8025 5800);
FORCEPROP 1 LAST WATTAGE 1/20W
J 0
(-8035 5925);
DISPLAY 0.787234 (-8035 5925);
FORCEPROP 1 LAST TOLERANCE 5%
J 0
(-8030 5975);
DISPLAY 0.787234 (-8030 5975);
FORCEPROP 1 LAST VALUE 4.7K
J 0
(-8030 6025);
DISPLAY 0.787234 (-8030 6025);
FORCEPROP 2 LAST CDS_LIB pure_quanta
J 0
(-8075 5950);
DISPLAY INVISIBLE (-8075 5950);
FORCEPROP 1 LAST PATH I54
J 0
(-8025 6125);
DISPLAY 0.978723 (-8025 6125);
PAINT WHITE (-8025 6125);
DISPLAY INVISIBLE (-8025 6125);
FORCEPROP 1 LAST PART_NUMBER CS24701JE04
J 0
(-8035 5825);
DISPLAY 0.978723 (-8035 5825);
DISPLAY INVISIBLE (-8035 5825);
FORCEADD Q_RES..2
(-7775 5975);
FORCEPROP 1 LAST LOCATION R922
J 0
(-7730 6100);
DISPLAY 0.787234 (-7730 6100);
FORCEPROP 0 LAST $SEC 1
J 0
(-7725 6150);
DISPLAY 0.680851 (-7725 6150);
PAINT MONO (-7725 6150);
DISPLAY INVISIBLE (-7725 6150);
FORCEPROP 0 LAST CDS_SEC 1
J 0
(-7725 6150);
DISPLAY 0.680851 (-7725 6150);
DISPLAY INVISIBLE (-7725 6150);
FORCEPROP 1 LASTPIN (-7775 6075) $PN 1
J 0
(-7770 6037);
DISPLAY 0.787234 (-7770 6037);
PAINT MONO (-7770 6037);
FORCEPROP 1 LASTPIN (-7775 5875) $PN 2
J 0
(-7770 5885);
DISPLAY 0.787234 (-7770 5885);
PAINT MONO (-7770 5885);
FORCEPROP 1 LAST VALUE 4.7K
J 0
(-7730 6050);
DISPLAY 0.787234 (-7730 6050);
FORCEPROP 1 LAST WATTAGE 1/20W
J 0
(-7735 5950);
DISPLAY 0.787234 (-7735 5950);
FORCEPROP 1 LAST MATERIAL EMPTY
J 0
(-7735 5900);
DISPLAY 0.787234 (-7735 5900);
FORCEPROP 1 LAST PACK_TYPE 0201LF
J 0
(-7735 5800);
DISPLAY 0.787234 (-7735 5800);
FORCEPROP 1 LAST TOLERANCE 5%
J 0
(-7730 6000);
DISPLAY 0.787234 (-7730 6000);
FORCEPROP 2 LAST CDS_LIB pure_quanta
J 0
(-7775 5975);
DISPLAY INVISIBLE (-7775 5975);
FORCEPROP 1 LAST PATH I55
J 0
(-7725 6150);
DISPLAY 0.978723 (-7725 6150);
PAINT WHITE (-7725 6150);
DISPLAY INVISIBLE (-7725 6150);
FORCEPROP 1 LAST PART_NUMBER CS24701JE04
J 0
(-7735 5850);
DISPLAY 0.787234 (-7735 5850);
DISPLAY INVISIBLE (-7735 5850);
FORCEADD Q_RES..2
(-7475 6000);
FORCEPROP 1 LAST LOCATION R912
J 0
(-7430 6125);
DISPLAY 0.787234 (-7430 6125);
FORCEPROP 0 LAST $SEC 1
J 0
(-7425 6175);
DISPLAY 0.680851 (-7425 6175);
PAINT MONO (-7425 6175);
DISPLAY INVISIBLE (-7425 6175);
FORCEPROP 0 LAST CDS_SEC 1
J 0
(-7425 6175);
DISPLAY 0.680851 (-7425 6175);
DISPLAY INVISIBLE (-7425 6175);
FORCEPROP 1 LASTPIN (-7475 6100) $PN 1
J 0
(-7470 6062);
DISPLAY 0.787234 (-7470 6062);
PAINT MONO (-7470 6062);
FORCEPROP 1 LASTPIN (-7475 5900) $PN 2
J 0
(-7470 5910);
DISPLAY 0.787234 (-7470 5910);
PAINT MONO (-7470 5910);
FORCEPROP 1 LAST PACK_TYPE 0201LF
J 0
(-7425 5825);
DISPLAY 0.787234 (-7425 5825);
FORCEPROP 1 LAST WATTAGE 1/20W
J 0
(-7435 5975);
DISPLAY 0.787234 (-7435 5975);
FORCEPROP 1 LAST MATERIAL EMPTY
J 0
(-7435 5925);
DISPLAY 0.787234 (-7435 5925);
FORCEPROP 1 LAST TOLERANCE 5%
J 0
(-7430 6025);
DISPLAY 0.787234 (-7430 6025);
FORCEPROP 1 LAST VALUE 4.7K
J 0
(-7430 6075);
DISPLAY 0.787234 (-7430 6075);
FORCEPROP 2 LAST CDS_LIB pure_quanta
J 0
(-7475 6000);
DISPLAY INVISIBLE (-7475 6000);
FORCEPROP 1 LAST PATH I56
J 0
(-7425 6175);
DISPLAY 0.978723 (-7425 6175);
PAINT WHITE (-7425 6175);
DISPLAY INVISIBLE (-7425 6175);
FORCEPROP 1 LAST PART_NUMBER CS24701JE04
J 0
(-7425 5875);
DISPLAY 0.638298 (-7425 5875);
DISPLAY INVISIBLE (-7425 5875);
FORCEADD OFFPAGE..5
R 2
(-6425 5575);
FORCEPROP 2 LAST $XR0 354 
J 0
(-6236 5575);
DISPLAY 0.638298 (-6236 5575);
PAINT MONO (-6236 5575);
FORCEPROP 2 LAST CDS_LIB standard
J 0
(-6425 5575);
DISPLAY INVISIBLE (-6425 5575);
FORCEPROP 1 LAST OFFPAGE TRUE
J 2
(-6750 5450);
DISPLAY 0.872340 (-6750 5450);
PAINT GREEN (-6750 5450);
DISPLAY INVISIBLE (-6750 5450);
FORCEPROP 1 LAST COMMENT_BODY TRUE
J 2
(-6525 5500);
DISPLAY 0.872340 (-6525 5500);
PAINT GREEN (-6525 5500);
DISPLAY INVISIBLE (-6525 5500);
FORCEPROP 2 LAST PATH I57
J 0
(-6225 5625);
DISPLAY 0.680851 (-6225 5625);
DISPLAY INVISIBLE (-6225 5625);
FORCEADD OFFPAGE..5
R 2
(-6425 5625);
FORCEPROP 2 LAST $XR0 354 
J 0
(-6236 5625);
DISPLAY 0.638298 (-6236 5625);
PAINT MONO (-6236 5625);
FORCEPROP 2 LAST CDS_LIB standard
J 0
(-6425 5625);
DISPLAY INVISIBLE (-6425 5625);
FORCEPROP 1 LAST OFFPAGE TRUE
J 2
(-6750 5500);
DISPLAY 0.872340 (-6750 5500);
PAINT GREEN (-6750 5500);
DISPLAY INVISIBLE (-6750 5500);
FORCEPROP 1 LAST COMMENT_BODY TRUE
J 2
(-6525 5550);
DISPLAY 0.872340 (-6525 5550);
PAINT GREEN (-6525 5550);
DISPLAY INVISIBLE (-6525 5550);
FORCEPROP 2 LAST PATH I58
J 0
(-6225 5675);
DISPLAY 0.680851 (-6225 5675);
DISPLAY INVISIBLE (-6225 5675);
FORCEADD OFFPAGE..5
R 2
(-6425 5525);
FORCEPROP 2 LAST $XR0 354 
J 0
(-6236 5525);
DISPLAY 0.638298 (-6236 5525);
PAINT MONO (-6236 5525);
FORCEPROP 2 LAST CDS_LIB standard
J 0
(-6425 5525);
DISPLAY INVISIBLE (-6425 5525);
FORCEPROP 1 LAST OFFPAGE TRUE
J 2
(-6750 5400);
DISPLAY 0.872340 (-6750 5400);
PAINT GREEN (-6750 5400);
DISPLAY INVISIBLE (-6750 5400);
FORCEPROP 1 LAST COMMENT_BODY TRUE
J 2
(-6525 5450);
DISPLAY 0.872340 (-6525 5450);
PAINT GREEN (-6525 5450);
DISPLAY INVISIBLE (-6525 5450);
FORCEPROP 2 LAST PATH I59
J 0
(-6225 5575);
DISPLAY 0.680851 (-6225 5575);
DISPLAY INVISIBLE (-6225 5575);
FORCEADD OFFPAGE..5
R 2
(-6425 5475);
FORCEPROP 2 LAST $XR0 354 
J 0
(-6236 5475);
DISPLAY 0.638298 (-6236 5475);
PAINT MONO (-6236 5475);
FORCEPROP 2 LAST CDS_LIB standard
J 0
(-6425 5475);
DISPLAY INVISIBLE (-6425 5475);
FORCEPROP 1 LAST OFFPAGE TRUE
J 2
(-6750 5350);
DISPLAY 0.872340 (-6750 5350);
PAINT GREEN (-6750 5350);
DISPLAY INVISIBLE (-6750 5350);
FORCEPROP 1 LAST COMMENT_BODY TRUE
J 2
(-6525 5400);
DISPLAY 0.872340 (-6525 5400);
PAINT GREEN (-6525 5400);
DISPLAY INVISIBLE (-6525 5400);
FORCEPROP 2 LAST PATH I60
J 0
(-6225 5525);
DISPLAY 0.680851 (-6225 5525);
DISPLAY INVISIBLE (-6225 5525);
FORCEADD OFFPAGE..5
R 2
(-6425 5400);
FORCEPROP 2 LAST $XR0 354 
J 0
(-6236 5400);
DISPLAY 0.638298 (-6236 5400);
PAINT MONO (-6236 5400);
FORCEPROP 2 LAST CDS_LIB standard
J 0
(-6425 5400);
DISPLAY INVISIBLE (-6425 5400);
FORCEPROP 1 LAST OFFPAGE TRUE
J 2
(-6750 5275);
DISPLAY 0.872340 (-6750 5275);
PAINT GREEN (-6750 5275);
DISPLAY INVISIBLE (-6750 5275);
FORCEPROP 1 LAST COMMENT_BODY TRUE
J 2
(-6525 5325);
DISPLAY 0.872340 (-6525 5325);
PAINT GREEN (-6525 5325);
DISPLAY INVISIBLE (-6525 5325);
FORCEPROP 2 LAST PATH I61
J 0
(-6225 5450);
DISPLAY 0.680851 (-6225 5450);
DISPLAY INVISIBLE (-6225 5450);
FORCEADD OFFPAGE..5
R 2
(-6425 5700);
FORCEPROP 2 LAST $XR0 354 
J 0
(-6236 5700);
DISPLAY 0.638298 (-6236 5700);
PAINT MONO (-6236 5700);
FORCEPROP 2 LAST CDS_LIB standard
J 0
(-6425 5700);
DISPLAY INVISIBLE (-6425 5700);
FORCEPROP 1 LAST OFFPAGE TRUE
J 2
(-6750 5575);
DISPLAY 0.872340 (-6750 5575);
PAINT GREEN (-6750 5575);
DISPLAY INVISIBLE (-6750 5575);
FORCEPROP 1 LAST COMMENT_BODY TRUE
J 2
(-6525 5625);
DISPLAY 0.872340 (-6525 5625);
PAINT GREEN (-6525 5625);
DISPLAY INVISIBLE (-6525 5625);
FORCEPROP 2 LAST PATH I62
J 0
(-6225 5750);
DISPLAY 0.680851 (-6225 5750);
DISPLAY INVISIBLE (-6225 5750);
FORCEADD UNIVERSAL_GND..1
(-5075 5200);
FORCEPROP 3 LASTPIN (-5075 5250) SIG_NAME GND\g
J 0
(-5065 5260);
DISPLAY 0.659574 (-5065 5260);
PAINT MONO (-5065 5260);
DISPLAY INVISIBLE (-5065 5260);
FORCEPROP 2 LAST CDS_LIB pure_quanta_power
J 0
(-5075 5200);
DISPLAY INVISIBLE (-5075 5200);
FORCEPROP 1 LAST HDL_POWER GND
J 1
(-5050 5125);
DISPLAY 0.872340 (-5050 5125);
PAINT GREEN (-5050 5125);
DISPLAY INVISIBLE (-5050 5125);
FORCEPROP 1 LAST PATH I63
J 0
(-5000 5200);
DISPLAY 0.872340 (-5000 5200);
PAINT AQUA (-5000 5200);
DISPLAY INVISIBLE (-5000 5200);
FORCEADD Q_RES..2
(-5075 5550);
FORCEPROP 1 LAST LOCATION R926
J 0
(-5030 5675);
DISPLAY 0.787234 (-5030 5675);
FORCEPROP 0 LAST $SEC 1
J 0
(-5025 5725);
DISPLAY 0.680851 (-5025 5725);
PAINT MONO (-5025 5725);
DISPLAY INVISIBLE (-5025 5725);
FORCEPROP 0 LAST CDS_SEC 1
J 0
(-5025 5725);
DISPLAY 0.680851 (-5025 5725);
DISPLAY INVISIBLE (-5025 5725);
FORCEPROP 1 LASTPIN (-5075 5650) $PN 1
J 0
(-5070 5612);
DISPLAY 0.787234 (-5070 5612);
PAINT MONO (-5070 5612);
FORCEPROP 1 LASTPIN (-5075 5450) $PN 2
J 0
(-5070 5460);
DISPLAY 0.787234 (-5070 5460);
PAINT MONO (-5070 5460);
FORCEPROP 1 LAST MATERIAL EMPTY
J 0
(-5035 5475);
DISPLAY 0.787234 (-5035 5475);
FORCEPROP 1 LAST TOLERANCE 5%
J 0
(-5030 5575);
DISPLAY 0.787234 (-5030 5575);
FORCEPROP 1 LAST PACK_TYPE 0201LF
J 0
(-5035 5375);
DISPLAY 0.787234 (-5035 5375);
FORCEPROP 1 LAST WATTAGE 1/20W
J 0
(-5035 5525);
DISPLAY 0.787234 (-5035 5525);
FORCEPROP 1 LAST VALUE 4.7K
J 0
(-5030 5625);
DISPLAY 0.787234 (-5030 5625);
FORCEPROP 2 LAST CDS_LIB pure_quanta
J 0
(-5075 5550);
DISPLAY INVISIBLE (-5075 5550);
FORCEPROP 1 LAST PATH I64
J 0
(-5025 5725);
DISPLAY 0.978723 (-5025 5725);
PAINT WHITE (-5025 5725);
DISPLAY INVISIBLE (-5025 5725);
FORCEPROP 1 LAST PART_NUMBER CS24701JE04
J 0
(-5035 5425);
DISPLAY 0.787234 (-5035 5425);
DISPLAY INVISIBLE (-5035 5425);
FORCEADD Q_RES..2
(-5075 6075);
FORCEPROP 1 LAST LOCATION R925
J 0
(-5030 6200);
DISPLAY 0.787234 (-5030 6200);
FORCEPROP 0 LAST $SEC 1
J 0
(-5025 6250);
DISPLAY 0.680851 (-5025 6250);
PAINT MONO (-5025 6250);
DISPLAY INVISIBLE (-5025 6250);
FORCEPROP 0 LAST CDS_SEC 1
J 0
(-5025 6250);
DISPLAY 0.680851 (-5025 6250);
DISPLAY INVISIBLE (-5025 6250);
FORCEPROP 1 LASTPIN (-5075 6175) $PN 1
J 0
(-5070 6137);
DISPLAY 0.787234 (-5070 6137);
PAINT MONO (-5070 6137);
FORCEPROP 1 LASTPIN (-5075 5975) $PN 2
J 0
(-5070 5985);
DISPLAY 0.787234 (-5070 5985);
PAINT MONO (-5070 5985);
FORCEPROP 1 LAST VALUE 4.7K
J 0
(-5030 6150);
DISPLAY 0.787234 (-5030 6150);
FORCEPROP 1 LAST TOLERANCE 5%
J 0
(-5030 6100);
DISPLAY 0.787234 (-5030 6100);
FORCEPROP 1 LAST WATTAGE 1/20W
J 0
(-5035 6050);
DISPLAY 0.787234 (-5035 6050);
FORCEPROP 1 LAST MATERIAL CHIP
J 0
(-5035 6000);
DISPLAY 0.787234 (-5035 6000);
FORCEPROP 1 LAST PACK_TYPE 0201LF
J 0
(-5035 5900);
DISPLAY 0.787234 (-5035 5900);
FORCEPROP 2 LAST CDS_LIB pure_quanta
J 0
(-5075 6075);
DISPLAY INVISIBLE (-5075 6075);
FORCEPROP 1 LAST PATH I65
J 0
(-5025 6250);
DISPLAY 0.978723 (-5025 6250);
PAINT WHITE (-5025 6250);
DISPLAY INVISIBLE (-5025 6250);
FORCEPROP 1 LAST PART_NUMBER CS24701JE04
J 0
(-5035 5950);
DISPLAY 0.787234 (-5035 5950);
DISPLAY INVISIBLE (-5035 5950);
FORCEADD OFFPAGE..5
R 2
(-4200 5800);
FORCEPROP 2 LAST $XR0 354 
J 0
(-4011 5800);
DISPLAY 0.638298 (-4011 5800);
PAINT MONO (-4011 5800);
FORCEPROP 2 LAST CDS_LIB standard
J 0
(-4200 5800);
DISPLAY INVISIBLE (-4200 5800);
FORCEPROP 1 LAST OFFPAGE TRUE
J 2
(-4525 5675);
DISPLAY 0.872340 (-4525 5675);
PAINT GREEN (-4525 5675);
DISPLAY INVISIBLE (-4525 5675);
FORCEPROP 1 LAST COMMENT_BODY TRUE
J 2
(-4300 5725);
DISPLAY 0.872340 (-4300 5725);
PAINT GREEN (-4300 5725);
DISPLAY INVISIBLE (-4300 5725);
FORCEPROP 2 LAST PATH I66
J 0
(-4000 5850);
DISPLAY 0.680851 (-4000 5850);
DISPLAY INVISIBLE (-4000 5850);
FORCEADD P1V0..1
(-5075 6400);
FORCEPROP 3 LASTPIN (-5075 6350) SIG_NAME P1V8_CPU1_RT_1D\g
J 0
(-5065 6360);
DISPLAY 0.659574 (-5065 6360);
PAINT MONO (-5065 6360);
DISPLAY INVISIBLE (-5065 6360);
FORCEPROP 1 LAST HDL_POWER P1V8_CPU1_RT_1D
J 1
(-5075 6450);
DISPLAY 0.489362 (-5075 6450);
PAINT SKYBLUE (-5075 6450);
FORCEPROP 2 LAST CDS_LIB pure_quanta_power
J 0
(-5075 6400);
DISPLAY INVISIBLE (-5075 6400);
FORCEPROP 1 LAST PATH I67
J 0
(-5025 6425);
DISPLAY 0.872340 (-5025 6425);
PAINT AQUA (-5025 6425);
DISPLAY INVISIBLE (-5025 6425);
FORCEADD UNIVERSAL_GND..1
R 1
(-2675 1700);
FORCEPROP 3 LASTPIN (-2725 1700) SIG_NAME GND\g
J 0
(-2715 1710);
DISPLAY 0.659574 (-2715 1710);
PAINT MONO (-2715 1710);
DISPLAY INVISIBLE (-2715 1710);
FORCEPROP 2 LAST CDS_LIB pure_quanta_power
J 0
(-2675 1700);
DISPLAY INVISIBLE (-2675 1700);
FORCEPROP 1 LAST HDL_POWER GND
R 1
J 1
(-2600 1725);
DISPLAY 0.872340 (-2600 1725);
PAINT GREEN (-2600 1725);
DISPLAY INVISIBLE (-2600 1725);
FORCEPROP 1 LAST PATH I68
R 1
J 0
(-2675 1775);
DISPLAY 0.872340 (-2675 1775);
PAINT AQUA (-2675 1775);
DISPLAY INVISIBLE (-2675 1775);
FORCEADD Q_RES..1
(-2625 2200);
FORCEPROP 1 LAST LOCATION R895
J 0
(-2900 2200);
DISPLAY 0.978723 (-2900 2200);
FORCEPROP 2 LAST SEC 1
J 0
(-2675 2400);
DISPLAY 0.680851 (-2675 2400);
PAINT MONO (-2675 2400);
DISPLAY INVISIBLE (-2675 2400);
FORCEPROP 1 LASTPIN (-2725 2200) $PN 1
J 0
(-2713 2212);
DISPLAY 0.787234 (-2713 2212);
PAINT MONO (-2713 2212);
FORCEPROP 1 LASTPIN (-2525 2200) $PN 2
J 0
(-2563 2212);
DISPLAY 0.787234 (-2563 2212);
PAINT MONO (-2563 2212);
FORCEPROP 1 LAST PACK_TYPE 0201LF
J 0
(-2325 2200);
DISPLAY 0.787234 (-2325 2200);
FORCEPROP 1 LAST VALUE 0
J 2
(-2425 2200);
DISPLAY 0.787234 (-2425 2200);
FORCEPROP 1 LAST WATTAGE 1/20W
J 2
(-2825 2275);
DISPLAY 0.787234 (-2825 2275);
DISPLAY INVISIBLE (-2825 2275);
FORCEPROP 1 LAST TOLERANCE 5%
J 0
(-2800 2325);
DISPLAY 0.787234 (-2800 2325);
DISPLAY INVISIBLE (-2800 2325);
FORCEPROP 1 LAST MATERIAL CHIP
J 0
(-2800 2275);
DISPLAY 0.787234 (-2800 2275);
DISPLAY INVISIBLE (-2800 2275);
FORCEPROP 2 LAST SEC_TYPE 0201LF
J 0
(-2675 2400);
DISPLAY 0.680851 (-2675 2400);
DISPLAY INVISIBLE (-2675 2400);
FORCEPROP 2 LAST CDS_LIB pure_quanta
J 0
(-2625 2200);
DISPLAY INVISIBLE (-2625 2200);
FORCEPROP 1 LAST PATH I69
J 0
(-2675 2350);
DISPLAY 0.978723 (-2675 2350);
PAINT WHITE (-2675 2350);
DISPLAY INVISIBLE (-2675 2350);
FORCEPROP 1 LAST PART_NUMBER CS00001JE10
J 0
(-2675 2325);
DISPLAY 0.808511 (-2675 2325);
DISPLAY INVISIBLE (-2675 2325);
FORCEADD Q_RES..1
(-2625 2100);
FORCEPROP 1 LAST LOCATION R901
J 0
(-2900 2100);
DISPLAY 0.978723 (-2900 2100);
FORCEPROP 0 LAST $SEC 1
J 0
(-2325 2150);
DISPLAY 0.680851 (-2325 2150);
PAINT MONO (-2325 2150);
DISPLAY INVISIBLE (-2325 2150);
FORCEPROP 0 LAST CDS_SEC 1
J 0
(-2325 2150);
DISPLAY 0.680851 (-2325 2150);
DISPLAY INVISIBLE (-2325 2150);
FORCEPROP 1 LASTPIN (-2725 2100) $PN 1
J 0
(-2713 2112);
DISPLAY 0.787234 (-2713 2112);
PAINT MONO (-2713 2112);
FORCEPROP 1 LASTPIN (-2525 2100) $PN 2
J 0
(-2563 2112);
DISPLAY 0.787234 (-2563 2112);
PAINT MONO (-2563 2112);
FORCEPROP 1 LAST PACK_TYPE 0201LF
J 0
(-2325 2100);
DISPLAY 0.787234 (-2325 2100);
FORCEPROP 1 LAST VALUE 0
J 2
(-2425 2100);
DISPLAY 0.787234 (-2425 2100);
FORCEPROP 2 LAST CDS_LIB pure_quanta
J 0
(-2625 2100);
DISPLAY INVISIBLE (-2625 2100);
FORCEPROP 1 LAST MATERIAL CHIP
J 0
(-2800 2175);
DISPLAY 0.787234 (-2800 2175);
DISPLAY INVISIBLE (-2800 2175);
FORCEPROP 1 LAST TOLERANCE 5%
J 0
(-2800 2225);
DISPLAY 0.787234 (-2800 2225);
DISPLAY INVISIBLE (-2800 2225);
FORCEPROP 1 LAST WATTAGE 1/20W
J 2
(-2825 2175);
DISPLAY 0.787234 (-2825 2175);
DISPLAY INVISIBLE (-2825 2175);
FORCEPROP 1 LAST PATH I70
J 0
(-2675 2250);
DISPLAY 0.978723 (-2675 2250);
PAINT WHITE (-2675 2250);
DISPLAY INVISIBLE (-2675 2250);
FORCEPROP 1 LAST PART_NUMBER CS00001JE10
J 0
(-2675 2225);
DISPLAY 0.808511 (-2675 2225);
DISPLAY INVISIBLE (-2675 2225);
FORCEADD OFFPAGE..1
R 2
(-2425 2600);
FORCEPROP 2 LAST $XR0 354 
J 0
(-2239 2600);
DISPLAY 0.638298 (-2239 2600);
PAINT MONO (-2239 2600);
FORCEPROP 2 LAST CDS_LIB standard
J 0
(-2425 2600);
DISPLAY INVISIBLE (-2425 2600);
FORCEPROP 1 LAST OFFPAGE TRUE
J 2
(-2750 2475);
DISPLAY 0.872340 (-2750 2475);
DISPLAY INVISIBLE (-2750 2475);
FORCEPROP 1 LAST COMMENT_BODY TRUE
J 2
(-2550 2500);
DISPLAY 0.872340 (-2550 2500);
PAINT GREEN (-2550 2500);
DISPLAY INVISIBLE (-2550 2500);
FORCEPROP 2 LAST PATH I72
J 0
(-2225 2650);
DISPLAY 0.680851 (-2225 2650);
DISPLAY INVISIBLE (-2225 2650);
FORCEADD OFFPAGE..1
R 2
(-2450 2800);
FORCEPROP 2 LAST $XR0 354 
J 0
(-2264 2800);
DISPLAY 0.638298 (-2264 2800);
PAINT MONO (-2264 2800);
FORCEPROP 2 LAST CDS_LIB standard
J 2
(-2450 2800);
DISPLAY INVISIBLE (-2450 2800);
FORCEPROP 1 LAST OFFPAGE TRUE
J 2
(-2775 2675);
DISPLAY 0.872340 (-2775 2675);
DISPLAY INVISIBLE (-2775 2675);
FORCEPROP 1 LAST COMMENT_BODY TRUE
J 2
(-2575 2700);
DISPLAY 0.872340 (-2575 2700);
PAINT GREEN (-2575 2700);
DISPLAY INVISIBLE (-2575 2700);
FORCEPROP 2 LAST PATH I73
J 0
(-2250 2850);
DISPLAY 0.680851 (-2250 2850);
DISPLAY INVISIBLE (-2250 2850);
FORCEADD OFFPAGE..1
R 2
(-2525 3100);
FORCEPROP 2 LAST $XR0 354 
J 0
(-2339 3100);
DISPLAY 0.638298 (-2339 3100);
PAINT MONO (-2339 3100);
FORCEPROP 2 LAST CDS_LIB standard
J 0
(-2525 3100);
DISPLAY INVISIBLE (-2525 3100);
FORCEPROP 1 LAST OFFPAGE TRUE
J 2
(-2850 2975);
DISPLAY 0.872340 (-2850 2975);
DISPLAY INVISIBLE (-2850 2975);
FORCEPROP 1 LAST COMMENT_BODY TRUE
J 2
(-2650 3000);
DISPLAY 0.872340 (-2650 3000);
PAINT GREEN (-2650 3000);
DISPLAY INVISIBLE (-2650 3000);
FORCEPROP 2 LAST PATH I74
J 0
(-2325 3150);
DISPLAY 0.680851 (-2325 3150);
DISPLAY INVISIBLE (-2325 3150);
FORCEADD OFFPAGE..1
R 2
(-1100 2100);
FORCEPROP 2 LAST $XR1 354 
J 0
(-824 2100);
DISPLAY 0.638298 (-824 2100);
PAINT MONO (-824 2100);
FORCEPROP 2 LAST $XR0 81 
J 0
(-914 2100);
DISPLAY 0.638298 (-914 2100);
PAINT MONO (-914 2100);
FORCEPROP 2 LAST CDS_LIB standard
J 0
(-1100 2100);
DISPLAY INVISIBLE (-1100 2100);
FORCEPROP 1 LAST OFFPAGE TRUE
J 2
(-1425 1975);
DISPLAY 0.872340 (-1425 1975);
DISPLAY INVISIBLE (-1425 1975);
FORCEPROP 1 LAST COMMENT_BODY TRUE
J 2
(-1225 2000);
DISPLAY 0.872340 (-1225 2000);
PAINT GREEN (-1225 2000);
DISPLAY INVISIBLE (-1225 2000);
FORCEPROP 2 LAST PATH I76
J 0
(-800 2150);
DISPLAY 0.680851 (-800 2150);
DISPLAY INVISIBLE (-800 2150);
FORCEADD OFFPAGE..1
R 2
(-1100 2200);
FORCEPROP 2 LAST $XR1 354 
J 0
(-824 2200);
DISPLAY 0.638298 (-824 2200);
PAINT MONO (-824 2200);
FORCEPROP 2 LAST $XR0 81 
J 0
(-914 2200);
DISPLAY 0.638298 (-914 2200);
PAINT MONO (-914 2200);
FORCEPROP 2 LAST CDS_LIB standard
J 0
(-1100 2200);
DISPLAY INVISIBLE (-1100 2200);
FORCEPROP 1 LAST OFFPAGE TRUE
J 2
(-1425 2075);
DISPLAY 0.872340 (-1425 2075);
DISPLAY INVISIBLE (-1425 2075);
FORCEPROP 1 LAST COMMENT_BODY TRUE
J 2
(-1225 2100);
DISPLAY 0.872340 (-1225 2100);
PAINT GREEN (-1225 2100);
DISPLAY INVISIBLE (-1225 2100);
FORCEPROP 2 LAST PATH I77
J 0
(-800 2250);
DISPLAY 0.680851 (-800 2250);
DISPLAY INVISIBLE (-800 2250);
FORCEADD UNIVERSAL_GND..1
(-3675 4900);
FORCEPROP 3 LASTPIN (-3675 4950) SIG_NAME GND\g
J 0
(-3665 4960);
DISPLAY 0.659574 (-3665 4960);
PAINT MONO (-3665 4960);
DISPLAY INVISIBLE (-3665 4960);
FORCEPROP 2 LAST CDS_LIB pure_quanta_power
J 0
(-3675 4900);
DISPLAY INVISIBLE (-3675 4900);
FORCEPROP 1 LAST HDL_POWER GND
J 1
(-3650 4825);
DISPLAY 0.872340 (-3650 4825);
PAINT GREEN (-3650 4825);
DISPLAY INVISIBLE (-3650 4825);
FORCEPROP 1 LAST PATH I78
J 0
(-3600 4900);
DISPLAY 0.872340 (-3600 4900);
PAINT AQUA (-3600 4900);
DISPLAY INVISIBLE (-3600 4900);
FORCEADD Q_RES..2
(-3675 5325);
FORCEPROP 1 LAST LOCATION R903
J 0
(-3630 5450);
DISPLAY 0.787234 (-3630 5450);
FORCEPROP 0 LAST $SEC 1
J 0
(-3625 5500);
DISPLAY 0.680851 (-3625 5500);
PAINT MONO (-3625 5500);
DISPLAY INVISIBLE (-3625 5500);
FORCEPROP 0 LAST CDS_SEC 1
J 0
(-3625 5500);
DISPLAY 0.680851 (-3625 5500);
DISPLAY INVISIBLE (-3625 5500);
FORCEPROP 1 LASTPIN (-3675 5425) $PN 1
J 0
(-3670 5387);
DISPLAY 0.787234 (-3670 5387);
PAINT MONO (-3670 5387);
FORCEPROP 1 LASTPIN (-3675 5225) $PN 2
J 0
(-3670 5235);
DISPLAY 0.787234 (-3670 5235);
PAINT MONO (-3670 5235);
FORCEPROP 1 LAST MATERIAL EMPTY
J 0
(-3635 5250);
DISPLAY 0.787234 (-3635 5250);
FORCEPROP 1 LAST PACK_TYPE 0201LF
J 0
(-3635 5150);
DISPLAY 0.787234 (-3635 5150);
FORCEPROP 1 LAST WATTAGE 1/20W
J 0
(-3635 5300);
DISPLAY 0.787234 (-3635 5300);
FORCEPROP 1 LAST TOLERANCE 1%
J 0
(-3630 5350);
DISPLAY 0.787234 (-3630 5350);
FORCEPROP 1 LAST VALUE 1K
J 0
(-3630 5400);
DISPLAY 0.787234 (-3630 5400);
FORCEPROP 2 LAST CDS_LIB pure_quanta
J 0
(-3675 5325);
DISPLAY INVISIBLE (-3675 5325);
FORCEPROP 1 LAST PATH I79
J 0
(-3625 5500);
DISPLAY 0.978723 (-3625 5500);
PAINT WHITE (-3625 5500);
DISPLAY INVISIBLE (-3625 5500);
FORCEPROP 1 LAST PART_NUMBER CS21001FE07
J 0
(-3635 5200);
DISPLAY 0.978723 (-3635 5200);
DISPLAY INVISIBLE (-3635 5200);
FORCEADD Q_RES..2
(-3675 6100);
FORCEPROP 1 LAST LOCATION R902
J 0
(-3630 6225);
DISPLAY 0.787234 (-3630 6225);
FORCEPROP 0 LAST $SEC 1
J 0
(-3625 6275);
DISPLAY 0.680851 (-3625 6275);
PAINT MONO (-3625 6275);
DISPLAY INVISIBLE (-3625 6275);
FORCEPROP 0 LAST CDS_SEC 1
J 0
(-3625 6275);
DISPLAY 0.680851 (-3625 6275);
DISPLAY INVISIBLE (-3625 6275);
FORCEPROP 1 LASTPIN (-3675 6200) $PN 1
J 0
(-3670 6162);
DISPLAY 0.787234 (-3670 6162);
PAINT MONO (-3670 6162);
FORCEPROP 1 LASTPIN (-3675 6000) $PN 2
J 0
(-3670 6010);
DISPLAY 0.787234 (-3670 6010);
PAINT MONO (-3670 6010);
FORCEPROP 1 LAST MATERIAL CHIP
J 0
(-3635 6025);
DISPLAY 0.787234 (-3635 6025);
FORCEPROP 1 LAST PACK_TYPE 0201LF
J 0
(-3635 5925);
DISPLAY 0.787234 (-3635 5925);
FORCEPROP 1 LAST WATTAGE 1/20W
J 0
(-3635 6075);
DISPLAY 0.787234 (-3635 6075);
FORCEPROP 1 LAST TOLERANCE 1%
J 0
(-3630 6125);
DISPLAY 0.787234 (-3630 6125);
FORCEPROP 1 LAST VALUE 1K
J 0
(-3630 6175);
DISPLAY 0.787234 (-3630 6175);
FORCEPROP 2 LAST CDS_LIB pure_quanta
J 0
(-3675 6100);
DISPLAY INVISIBLE (-3675 6100);
FORCEPROP 1 LAST PATH I80
J 0
(-3625 6275);
DISPLAY 0.978723 (-3625 6275);
PAINT WHITE (-3625 6275);
DISPLAY INVISIBLE (-3625 6275);
FORCEPROP 1 LAST PART_NUMBER CS21001FE07
J 0
(-3635 5975);
DISPLAY 0.978723 (-3635 5975);
DISPLAY INVISIBLE (-3635 5975);
FORCEADD Q_RES..2
(-3375 5325);
FORCEPROP 1 LAST LOCATION R906
J 0
(-3330 5450);
DISPLAY 0.787234 (-3330 5450);
FORCEPROP 0 LAST $SEC 1
J 0
(-3325 5500);
DISPLAY 0.680851 (-3325 5500);
PAINT MONO (-3325 5500);
DISPLAY INVISIBLE (-3325 5500);
FORCEPROP 0 LAST CDS_SEC 1
J 0
(-3325 5500);
DISPLAY 0.680851 (-3325 5500);
DISPLAY INVISIBLE (-3325 5500);
FORCEPROP 1 LASTPIN (-3375 5425) $PN 1
J 0
(-3370 5387);
DISPLAY 0.787234 (-3370 5387);
PAINT MONO (-3370 5387);
FORCEPROP 1 LASTPIN (-3375 5225) $PN 2
J 0
(-3370 5235);
DISPLAY 0.787234 (-3370 5235);
PAINT MONO (-3370 5235);
FORCEPROP 1 LAST VALUE 20K
J 0
(-3330 5400);
DISPLAY 0.787234 (-3330 5400);
FORCEPROP 1 LAST PACK_TYPE 0201LF
J 0
(-3335 5150);
DISPLAY 0.787234 (-3335 5150);
FORCEPROP 1 LAST WATTAGE 1/20W
J 0
(-3335 5300);
DISPLAY 0.787234 (-3335 5300);
FORCEPROP 1 LAST MATERIAL CHIP
J 0
(-3335 5250);
DISPLAY 0.787234 (-3335 5250);
FORCEPROP 1 LAST TOLERANCE 1%
J 0
(-3330 5350);
DISPLAY 0.787234 (-3330 5350);
FORCEPROP 2 LAST CDS_LIB pure_quanta
J 0
(-3375 5325);
DISPLAY INVISIBLE (-3375 5325);
FORCEPROP 1 LAST PATH I81
J 0
(-3325 5500);
DISPLAY 0.978723 (-3325 5500);
PAINT WHITE (-3325 5500);
DISPLAY INVISIBLE (-3325 5500);
FORCEPROP 1 LAST PART_NUMBER CS32001FE00
J 0
(-3335 5200);
DISPLAY 0.978723 (-3335 5200);
DISPLAY INVISIBLE (-3335 5200);
FORCEADD Q_RES..2
(-3375 6100);
FORCEPROP 1 LAST LOCATION R904
J 0
(-3330 6225);
DISPLAY 0.978723 (-3330 6225);
FORCEPROP 0 LAST $SEC 1
J 0
(-3325 6275);
DISPLAY 0.680851 (-3325 6275);
PAINT MONO (-3325 6275);
DISPLAY INVISIBLE (-3325 6275);
FORCEPROP 0 LAST CDS_SEC 1
J 0
(-3325 6275);
DISPLAY 0.680851 (-3325 6275);
DISPLAY INVISIBLE (-3325 6275);
FORCEPROP 1 LASTPIN (-3375 6200) $PN 1
J 0
(-3370 6162);
DISPLAY 0.787234 (-3370 6162);
PAINT MONO (-3370 6162);
FORCEPROP 1 LASTPIN (-3375 6000) $PN 2
J 0
(-3370 6010);
DISPLAY 0.787234 (-3370 6010);
PAINT MONO (-3370 6010);
FORCEPROP 1 LAST PACK_TYPE 0201LF
J 0
(-3335 5925);
DISPLAY 0.787234 (-3335 5925);
FORCEPROP 1 LAST MATERIAL EMPTY
J 0
(-3335 6025);
DISPLAY 0.787234 (-3335 6025);
FORCEPROP 1 LAST WATTAGE 1/20W
J 0
(-3335 6075);
DISPLAY 0.787234 (-3335 6075);
FORCEPROP 1 LAST VALUE 1K
J 0
(-3330 6175);
DISPLAY 0.787234 (-3330 6175);
FORCEPROP 1 LAST TOLERANCE 1%
J 0
(-3330 6125);
DISPLAY 0.787234 (-3330 6125);
FORCEPROP 2 LAST CDS_LIB pure_quanta
J 0
(-3375 6100);
DISPLAY INVISIBLE (-3375 6100);
FORCEPROP 1 LAST PATH I82
J 0
(-3325 6275);
DISPLAY 0.978723 (-3325 6275);
PAINT WHITE (-3325 6275);
DISPLAY INVISIBLE (-3325 6275);
FORCEPROP 1 LAST PART_NUMBER CS21001FE07
J 0
(-3335 5975);
DISPLAY 0.978723 (-3335 5975);
DISPLAY INVISIBLE (-3335 5975);
FORCEADD Q_RES..2
(-3025 5325);
FORCEPROP 1 LAST LOCATION R949
J 0
(-2980 5450);
DISPLAY 0.978723 (-2980 5450);
FORCEPROP 0 LAST $SEC 1
J 0
(-2975 5500);
DISPLAY 0.680851 (-2975 5500);
PAINT MONO (-2975 5500);
DISPLAY INVISIBLE (-2975 5500);
FORCEPROP 0 LAST CDS_SEC 1
J 0
(-2975 5500);
DISPLAY 0.680851 (-2975 5500);
DISPLAY INVISIBLE (-2975 5500);
FORCEPROP 1 LASTPIN (-3025 5425) $PN 1
J 0
(-3020 5387);
DISPLAY 0.787234 (-3020 5387);
PAINT MONO (-3020 5387);
FORCEPROP 1 LASTPIN (-3025 5225) $PN 2
J 0
(-3020 5235);
DISPLAY 0.787234 (-3020 5235);
PAINT MONO (-3020 5235);
FORCEPROP 1 LAST MATERIAL CHIP
J 0
(-2985 5250);
DISPLAY 0.787234 (-2985 5250);
FORCEPROP 1 LAST WATTAGE 1/20W
J 0
(-2985 5300);
DISPLAY 0.787234 (-2985 5300);
FORCEPROP 1 LAST VALUE 1K
J 0
(-2980 5400);
DISPLAY 0.787234 (-2980 5400);
FORCEPROP 1 LAST PACK_TYPE 0201LF
J 0
(-2985 5150);
DISPLAY 0.787234 (-2985 5150);
FORCEPROP 1 LAST TOLERANCE 1%
J 0
(-2980 5350);
DISPLAY 0.787234 (-2980 5350);
FORCEPROP 2 LAST CDS_LIB pure_quanta
J 0
(-3025 5325);
DISPLAY INVISIBLE (-3025 5325);
FORCEPROP 1 LAST PATH I83
J 0
(-2975 5500);
DISPLAY 0.978723 (-2975 5500);
PAINT WHITE (-2975 5500);
DISPLAY INVISIBLE (-2975 5500);
FORCEPROP 1 LAST PART_NUMBER CS21001FE07
J 0
(-2985 5200);
DISPLAY 0.978723 (-2985 5200);
DISPLAY INVISIBLE (-2985 5200);
FORCEADD Q_RES..2
(-3025 6075);
FORCEPROP 1 LAST LOCATION R927
J 0
(-2980 6200);
DISPLAY 0.978723 (-2980 6200);
FORCEPROP 0 LAST $SEC 1
J 0
(-2975 6250);
DISPLAY 0.680851 (-2975 6250);
PAINT MONO (-2975 6250);
DISPLAY INVISIBLE (-2975 6250);
FORCEPROP 0 LAST CDS_SEC 1
J 0
(-2975 6250);
DISPLAY 0.680851 (-2975 6250);
DISPLAY INVISIBLE (-2975 6250);
FORCEPROP 1 LASTPIN (-3025 6175) $PN 1
J 0
(-3020 6137);
DISPLAY 0.787234 (-3020 6137);
PAINT MONO (-3020 6137);
FORCEPROP 1 LASTPIN (-3025 5975) $PN 2
J 0
(-3020 5985);
DISPLAY 0.787234 (-3020 5985);
PAINT MONO (-3020 5985);
FORCEPROP 1 LAST WATTAGE 1/20W
J 0
(-2985 6050);
DISPLAY 0.787234 (-2985 6050);
FORCEPROP 1 LAST PACK_TYPE 0201LF
J 0
(-2985 5900);
DISPLAY 0.787234 (-2985 5900);
FORCEPROP 1 LAST VALUE 1K
J 0
(-2980 6150);
DISPLAY 0.787234 (-2980 6150);
FORCEPROP 1 LAST TOLERANCE 1%
J 0
(-2980 6100);
DISPLAY 0.787234 (-2980 6100);
FORCEPROP 1 LAST MATERIAL EMPTY
J 0
(-2985 6000);
DISPLAY 0.787234 (-2985 6000);
FORCEPROP 2 LAST CDS_LIB pure_quanta
J 0
(-3025 6075);
DISPLAY INVISIBLE (-3025 6075);
FORCEPROP 1 LAST PATH I84
J 0
(-2975 6250);
DISPLAY 0.978723 (-2975 6250);
PAINT WHITE (-2975 6250);
DISPLAY INVISIBLE (-2975 6250);
FORCEPROP 1 LAST PART_NUMBER CS21001FE07
J 0
(-2985 5950);
DISPLAY 0.978723 (-2985 5950);
DISPLAY INVISIBLE (-2985 5950);
FORCEADD OFFPAGE..5
R 2
(-2125 5575);
FORCEPROP 2 LAST $XR0 354 
J 0
(-1936 5575);
DISPLAY 0.638298 (-1936 5575);
PAINT MONO (-1936 5575);
FORCEPROP 2 LAST CDS_LIB standard
J 0
(-2125 5575);
DISPLAY INVISIBLE (-2125 5575);
FORCEPROP 1 LAST OFFPAGE TRUE
J 2
(-2450 5450);
DISPLAY 0.872340 (-2450 5450);
PAINT GREEN (-2450 5450);
DISPLAY INVISIBLE (-2450 5450);
FORCEPROP 1 LAST COMMENT_BODY TRUE
J 2
(-2225 5500);
DISPLAY 0.872340 (-2225 5500);
PAINT GREEN (-2225 5500);
DISPLAY INVISIBLE (-2225 5500);
FORCEPROP 2 LAST PATH I85
J 0
(-1925 5625);
DISPLAY 0.680851 (-1925 5625);
DISPLAY INVISIBLE (-1925 5625);
FORCEADD OFFPAGE..5
R 2
(-2125 5675);
FORCEPROP 2 LAST $XR0 354 
J 0
(-1936 5675);
DISPLAY 0.638298 (-1936 5675);
PAINT MONO (-1936 5675);
FORCEPROP 2 LAST CDS_LIB standard
J 0
(-2125 5675);
DISPLAY INVISIBLE (-2125 5675);
FORCEPROP 1 LAST OFFPAGE TRUE
J 2
(-2450 5550);
DISPLAY 0.872340 (-2450 5550);
PAINT GREEN (-2450 5550);
DISPLAY INVISIBLE (-2450 5550);
FORCEPROP 1 LAST COMMENT_BODY TRUE
J 2
(-2225 5600);
DISPLAY 0.872340 (-2225 5600);
PAINT GREEN (-2225 5600);
DISPLAY INVISIBLE (-2225 5600);
FORCEPROP 2 LAST PATH I86
J 0
(-1925 5725);
DISPLAY 0.680851 (-1925 5725);
DISPLAY INVISIBLE (-1925 5725);
FORCEADD OFFPAGE..5
R 2
(-2125 5775);
FORCEPROP 2 LAST $XR0 354 
J 0
(-1936 5775);
DISPLAY 0.638298 (-1936 5775);
PAINT MONO (-1936 5775);
FORCEPROP 2 LAST CDS_LIB standard
J 0
(-2125 5775);
DISPLAY INVISIBLE (-2125 5775);
FORCEPROP 1 LAST OFFPAGE TRUE
J 2
(-2450 5650);
DISPLAY 0.872340 (-2450 5650);
PAINT GREEN (-2450 5650);
DISPLAY INVISIBLE (-2450 5650);
FORCEPROP 1 LAST COMMENT_BODY TRUE
J 2
(-2225 5700);
DISPLAY 0.872340 (-2225 5700);
PAINT GREEN (-2225 5700);
DISPLAY INVISIBLE (-2225 5700);
FORCEPROP 2 LAST PATH I87
J 0
(-1925 5825);
DISPLAY 0.680851 (-1925 5825);
DISPLAY INVISIBLE (-1925 5825);
FORCEADD P1V0..1
(-3675 6525);
FORCEPROP 3 LASTPIN (-3675 6475) SIG_NAME P1V8_CPU1_RT_1D\g
J 0
(-3665 6485);
DISPLAY 0.659574 (-3665 6485);
PAINT MONO (-3665 6485);
DISPLAY INVISIBLE (-3665 6485);
FORCEPROP 1 LAST HDL_POWER P1V8_CPU1_RT_1D
J 1
(-3675 6575);
DISPLAY 0.489362 (-3675 6575);
PAINT SKYBLUE (-3675 6575);
FORCEPROP 2 LAST CDS_LIB pure_quanta_power
J 0
(-3675 6525);
DISPLAY INVISIBLE (-3675 6525);
FORCEPROP 1 LAST PATH I88
J 0
(-3625 6550);
DISPLAY 0.872340 (-3625 6550);
PAINT AQUA (-3625 6550);
DISPLAY INVISIBLE (-3625 6550);
FORCEADD GND..1
(-1525 4850);
FORCEPROP 3 LASTPIN (-1525 4900) SIG_NAME GND\g
J 0
(-1515 4910);
DISPLAY 0.659574 (-1515 4910);
PAINT MONO (-1515 4910);
DISPLAY INVISIBLE (-1515 4910);
FORCEPROP 2 LAST CDS_LIB pure_quanta_power
J 0
(-1525 4850);
DISPLAY INVISIBLE (-1525 4850);
FORCEPROP 1 LAST SIZE 1B
J 0
(-1450 4800);
DISPLAY 0.851064 (-1450 4800);
PAINT GREEN (-1450 4800);
DISPLAY INVISIBLE (-1450 4800);
FORCEPROP 2 LAST BOM_COST MEM
J 0
(-1625 4925);
DISPLAY 0.808511 (-1625 4925);
DISPLAY INVISIBLE (-1625 4925);
FORCEPROP 1 LAST HDL_POWER GND
J 0
(-1525 5000);
DISPLAY 0.851064 (-1525 5000);
PAINT GREEN (-1525 5000);
DISPLAY INVISIBLE (-1525 5000);
FORCEPROP 1 LAST PATH I89
J 0
(-1450 4850);
DISPLAY 0.872340 (-1450 4850);
PAINT AQUA (-1450 4850);
DISPLAY INVISIBLE (-1450 4850);
FORCEADD Q_RES..2
R 2
(-1525 5225);
FORCEPROP 1 LAST LOCATION R908
J 2
(-1570 5350);
DISPLAY 0.638298 (-1570 5350);
FORCEPROP 0 LAST $SEC 1
J 0
(-1550 5400);
DISPLAY 0.680851 (-1550 5400);
PAINT MONO (-1550 5400);
DISPLAY INVISIBLE (-1550 5400);
FORCEPROP 0 LAST CDS_SEC 1
J 0
(-1550 5400);
DISPLAY 0.680851 (-1550 5400);
DISPLAY INVISIBLE (-1550 5400);
FORCEPROP 1 LASTPIN (-1525 5325) $PN 1
J 2
(-1530 5287);
DISPLAY 0.787234 (-1530 5287);
PAINT MONO (-1530 5287);
FORCEPROP 1 LASTPIN (-1525 5125) $PN 2
J 2
(-1530 5135);
DISPLAY 0.787234 (-1530 5135);
PAINT MONO (-1530 5135);
FORCEPROP 1 LAST PACK_TYPE 0201LF
J 2
(-1565 5050);
DISPLAY 0.638298 (-1565 5050);
FORCEPROP 1 LAST VALUE 10K
J 2
(-1570 5300);
DISPLAY 0.638298 (-1570 5300);
FORCEPROP 1 LAST WATTAGE 1/20W
J 2
(-1565 5200);
DISPLAY 0.638298 (-1565 5200);
FORCEPROP 1 LAST TOLERANCE 1%
J 2
(-1570 5250);
DISPLAY 0.638298 (-1570 5250);
FORCEPROP 1 LAST MATERIAL CHIP
J 2
(-1565 5150);
DISPLAY 0.638298 (-1565 5150);
FORCEPROP 2 LAST CDS_LIB pure_quanta
J 2
(-1525 5225);
DISPLAY INVISIBLE (-1525 5225);
FORCEPROP 1 LAST PATH I90
J 2
(-1575 5400);
DISPLAY 0.978723 (-1575 5400);
PAINT WHITE (-1575 5400);
DISPLAY INVISIBLE (-1575 5400);
FORCEPROP 1 LAST PART_NUMBER CS31001FE17
J 2
(-1565 5100);
DISPLAY 0.638298 (-1565 5100);
DISPLAY INVISIBLE (-1565 5100);
FORCEADD GND..1
(-1350 4875);
FORCEPROP 3 LASTPIN (-1350 4925) SIG_NAME GND\g
J 0
(-1340 4935);
DISPLAY 0.659574 (-1340 4935);
PAINT MONO (-1340 4935);
DISPLAY INVISIBLE (-1340 4935);
FORCEPROP 1 LAST SIZE 1B
J 0
(-1275 4825);
DISPLAY 0.851064 (-1275 4825);
PAINT GREEN (-1275 4825);
DISPLAY INVISIBLE (-1275 4825);
FORCEPROP 2 LAST BOM_COST MEM
J 0
(-1450 4950);
DISPLAY 0.808511 (-1450 4950);
DISPLAY INVISIBLE (-1450 4950);
FORCEPROP 2 LAST CDS_LIB pure_quanta_power
J 0
(-1350 4875);
DISPLAY INVISIBLE (-1350 4875);
FORCEPROP 1 LAST HDL_POWER GND
J 0
(-1350 5025);
DISPLAY 0.851064 (-1350 5025);
PAINT GREEN (-1350 5025);
DISPLAY INVISIBLE (-1350 5025);
FORCEPROP 1 LAST PATH I91
J 0
(-1275 4875);
DISPLAY 0.872340 (-1275 4875);
PAINT AQUA (-1275 4875);
DISPLAY INVISIBLE (-1275 4875);
FORCEADD Q_RES..2
(-1350 5225);
FORCEPROP 1 LAST LOCATION R907
J 0
(-1305 5350);
DISPLAY 0.638298 (-1305 5350);
FORCEPROP 0 LAST $SEC 1
J 0
(-1300 5400);
DISPLAY 0.680851 (-1300 5400);
PAINT MONO (-1300 5400);
DISPLAY INVISIBLE (-1300 5400);
FORCEPROP 0 LAST CDS_SEC 1
J 0
(-1300 5400);
DISPLAY 0.680851 (-1300 5400);
DISPLAY INVISIBLE (-1300 5400);
FORCEPROP 1 LASTPIN (-1350 5325) $PN 1
J 0
(-1345 5287);
DISPLAY 0.787234 (-1345 5287);
PAINT MONO (-1345 5287);
FORCEPROP 1 LASTPIN (-1350 5125) $PN 2
J 0
(-1345 5135);
DISPLAY 0.787234 (-1345 5135);
PAINT MONO (-1345 5135);
FORCEPROP 1 LAST VALUE 10K
J 0
(-1305 5300);
DISPLAY 0.638298 (-1305 5300);
FORCEPROP 1 LAST TOLERANCE 1%
J 0
(-1305 5250);
DISPLAY 0.638298 (-1305 5250);
FORCEPROP 1 LAST PACK_TYPE 0201LF
J 0
(-1310 5050);
DISPLAY 0.638298 (-1310 5050);
FORCEPROP 1 LAST WATTAGE 1/20W
J 0
(-1310 5200);
DISPLAY 0.638298 (-1310 5200);
FORCEPROP 1 LAST MATERIAL CHIP
J 0
(-1310 5150);
DISPLAY 0.638298 (-1310 5150);
FORCEPROP 2 LAST CDS_LIB pure_quanta
J 0
(-1350 5225);
DISPLAY INVISIBLE (-1350 5225);
FORCEPROP 1 LAST PATH I92
J 0
(-1300 5400);
DISPLAY 0.978723 (-1300 5400);
PAINT WHITE (-1300 5400);
DISPLAY INVISIBLE (-1300 5400);
FORCEPROP 1 LAST PART_NUMBER CS31001FE17
J 0
(-1310 5100);
DISPLAY 0.638298 (-1310 5100);
DISPLAY INVISIBLE (-1310 5100);
FORCEADD Q_RES..2
R 2
(-1525 6050);
FORCEPROP 1 LAST LOCATION R911
J 2
(-1570 6175);
DISPLAY 0.787234 (-1570 6175);
FORCEPROP 0 LAST $SEC 1
J 0
(-1550 6225);
DISPLAY 0.680851 (-1550 6225);
PAINT MONO (-1550 6225);
DISPLAY INVISIBLE (-1550 6225);
FORCEPROP 0 LAST CDS_SEC 1
J 0
(-1550 6225);
DISPLAY 0.680851 (-1550 6225);
DISPLAY INVISIBLE (-1550 6225);
FORCEPROP 1 LASTPIN (-1525 6150) $PN 1
J 2
(-1530 6112);
DISPLAY 0.787234 (-1530 6112);
PAINT MONO (-1530 6112);
FORCEPROP 1 LASTPIN (-1525 5950) $PN 2
J 2
(-1530 5960);
DISPLAY 0.787234 (-1530 5960);
PAINT MONO (-1530 5960);
FORCEPROP 1 LAST PACK_TYPE 0201LF
J 2
(-1575 5900);
DISPLAY 0.787234 (-1575 5900);
FORCEPROP 1 LAST MATERIAL EMPTY
J 2
(-1565 5975);
DISPLAY 0.787234 (-1565 5975);
FORCEPROP 1 LAST VALUE 4.7K
J 2
(-1570 6125);
DISPLAY 0.787234 (-1570 6125);
FORCEPROP 1 LAST WATTAGE 1/20W
J 2
(-1565 6025);
DISPLAY 0.787234 (-1565 6025);
FORCEPROP 1 LAST TOLERANCE 5%
J 2
(-1570 6075);
DISPLAY 0.787234 (-1570 6075);
FORCEPROP 2 LAST CDS_LIB pure_quanta
J 2
(-1525 6050);
DISPLAY INVISIBLE (-1525 6050);
FORCEPROP 1 LAST PATH I93
J 2
(-1575 6225);
DISPLAY 0.978723 (-1575 6225);
PAINT WHITE (-1575 6225);
DISPLAY INVISIBLE (-1575 6225);
FORCEPROP 1 LAST PART_NUMBER CS24701JE04
J 2
(-1565 5925);
DISPLAY 0.978723 (-1565 5925);
DISPLAY INVISIBLE (-1565 5925);
FORCEADD OFFPAGE..1
R 2
(-550 5600);
FORCEPROP 2 LAST $XR1 354 
J 0
(-274 5600);
DISPLAY 0.638298 (-274 5600);
PAINT MONO (-274 5600);
FORCEPROP 2 LAST $XR0 81 
J 0
(-364 5600);
DISPLAY 0.638298 (-364 5600);
PAINT MONO (-364 5600);
FORCEPROP 2 LAST CDS_LIB standard
J 0
(-550 5600);
DISPLAY INVISIBLE (-550 5600);
FORCEPROP 1 LAST OFFPAGE TRUE
J 2
(-875 5475);
DISPLAY 0.872340 (-875 5475);
PAINT GREEN (-875 5475);
DISPLAY INVISIBLE (-875 5475);
FORCEPROP 1 LAST COMMENT_BODY TRUE
J 2
(-675 5500);
DISPLAY 0.872340 (-675 5500);
PAINT GREEN (-675 5500);
DISPLAY INVISIBLE (-675 5500);
FORCEPROP 2 LAST PATH I94
J 0
(-350 5650);
DISPLAY 0.680851 (-350 5650);
DISPLAY INVISIBLE (-350 5650);
FORCEADD OFFPAGE..1
R 2
(-575 5450);
FORCEPROP 2 LAST $XR1 354 
J 0
(-299 5450);
DISPLAY 0.638298 (-299 5450);
PAINT MONO (-299 5450);
FORCEPROP 2 LAST $XR0 81 
J 0
(-389 5450);
DISPLAY 0.638298 (-389 5450);
PAINT MONO (-389 5450);
FORCEPROP 2 LAST CDS_LIB standard
J 0
(-575 5450);
DISPLAY INVISIBLE (-575 5450);
FORCEPROP 1 LAST OFFPAGE TRUE
J 2
(-900 5325);
DISPLAY 0.872340 (-900 5325);
PAINT GREEN (-900 5325);
DISPLAY INVISIBLE (-900 5325);
FORCEPROP 1 LAST COMMENT_BODY TRUE
J 2
(-700 5350);
DISPLAY 0.872340 (-700 5350);
PAINT GREEN (-700 5350);
DISPLAY INVISIBLE (-700 5350);
FORCEPROP 2 LAST PATH I95
J 0
(-275 5500);
DISPLAY 0.680851 (-275 5500);
DISPLAY INVISIBLE (-275 5500);
FORCEADD P1V0..1
(-1525 6300);
FORCEPROP 3 LASTPIN (-1525 6250) SIG_NAME P1V8_CPU1_RT_1D\g
J 0
(-1515 6260);
DISPLAY 0.659574 (-1515 6260);
PAINT MONO (-1515 6260);
DISPLAY INVISIBLE (-1515 6260);
FORCEPROP 1 LAST HDL_POWER P1V8_CPU1_RT_1D
J 1
(-1525 6350);
DISPLAY 0.489362 (-1525 6350);
PAINT SKYBLUE (-1525 6350);
FORCEPROP 2 LAST CDS_LIB pure_quanta_power
J 0
(-1525 6300);
DISPLAY INVISIBLE (-1525 6300);
FORCEPROP 1 LAST PATH I96
J 0
(-1475 6325);
DISPLAY 0.872340 (-1475 6325);
PAINT AQUA (-1475 6325);
DISPLAY INVISIBLE (-1475 6325);
FORCEADD PT5161LRS..3
(-4425 2350);
FORCEPROP 1 LAST LOCATION U6017
J 0
(-4925 3975);
DISPLAY 0.723404 (-4925 3975);
PAINT SKYBLUE (-4925 3975);
FORCEPROP 0 LAST $SEC 3
J 0
(-4925 4125);
DISPLAY 0.680851 (-4925 4125);
PAINT MONO (-4925 4125);
DISPLAY INVISIBLE (-4925 4125);
FORCEPROP 0 LAST CDS_SEC 3
J 0
(-4925 4125);
DISPLAY 0.680851 (-4925 4125);
DISPLAY INVISIBLE (-4925 4125);
FORCEPROP 0 LASTPIN (-3825 2300) $PN G35
J 0
(-3815 2310);
DISPLAY 0.680851 (-3815 2310);
PAINT MONO (-3815 2310);
FORCEPROP 0 LASTPIN (-5075 1650) $PN FF5
J 2
(-5085 1660);
DISPLAY 0.680851 (-5085 1660);
PAINT MONO (-5085 1660);
FORCEPROP 0 LASTPIN (-5075 1550) $PN FJ3
J 2
(-5085 1560);
DISPLAY 0.680851 (-5085 1560);
PAINT MONO (-5085 1560);
FORCEPROP 0 LASTPIN (-5075 3550) $PN FJ6
J 2
(-5085 3560);
DISPLAY 0.680851 (-5085 3560);
PAINT MONO (-5085 3560);
FORCEPROP 0 LASTPIN (-5075 3450) $PN FJ23
J 2
(-5085 3460);
DISPLAY 0.680851 (-5085 3460);
PAINT MONO (-5085 3460);
FORCEPROP 0 LASTPIN (-5075 3350) $PN FJ25
J 2
(-5085 3360);
DISPLAY 0.680851 (-5085 3360);
PAINT MONO (-5085 3360);
FORCEPROP 0 LASTPIN (-5075 3250) $PN FJ28
J 2
(-5085 3260);
DISPLAY 0.680851 (-5085 3260);
PAINT MONO (-5085 3260);
FORCEPROP 0 LASTPIN (-3825 1900) $PN FJ31
J 0
(-3815 1910);
DISPLAY 0.680851 (-3815 1910);
PAINT MONO (-3815 1910);
FORCEPROP 0 LASTPIN (-3825 3650) $PN B3
J 0
(-3815 3660);
DISPLAY 0.680851 (-3815 3660);
PAINT MONO (-3815 3660);
FORCEPROP 0 LASTPIN (-3825 3350) $PN B6
J 0
(-3815 3360);
DISPLAY 0.680851 (-3815 3360);
PAINT MONO (-3815 3360);
FORCEPROP 0 LASTPIN (-3825 3550) $PN B9
J 0
(-3815 3560);
DISPLAY 0.680851 (-3815 3560);
PAINT MONO (-3815 3560);
FORCEPROP 0 LASTPIN (-3825 3100) $PN FF8
J 0
(-3815 3110);
DISPLAY 0.680851 (-3815 3110);
PAINT MONO (-3815 3110);
FORCEPROP 0 LASTPIN (-3825 3450) $PN B12
J 0
(-3815 3460);
DISPLAY 0.680851 (-3815 3460);
PAINT MONO (-3815 3460);
FORCEPROP 0 LASTPIN (-3825 3250) $PN E8
J 0
(-3815 3260);
DISPLAY 0.680851 (-3815 3260);
PAINT MONO (-3815 3260);
FORCEPROP 0 LASTPIN (-3825 2800) $PN FJ9
J 0
(-3815 2810);
DISPLAY 0.680851 (-3815 2810);
PAINT MONO (-3815 2810);
FORCEPROP 0 LASTPIN (-3825 2200) $PN F2
J 0
(-3815 2210);
DISPLAY 0.680851 (-3815 2210);
PAINT MONO (-3815 2210);
FORCEPROP 0 LASTPIN (-3825 1050) $PN E18
J 0
(-3815 1060);
DISPLAY 0.680851 (-3815 1060);
PAINT MONO (-3815 1060);
FORCEPROP 0 LASTPIN (-3825 1200) $PN B16
J 0
(-3815 1210);
DISPLAY 0.680851 (-3815 1210);
PAINT MONO (-3815 1210);
FORCEPROP 0 LASTPIN (-5075 1050) $PN FF18
J 2
(-5085 1060);
DISPLAY 0.680851 (-5085 1060);
PAINT MONO (-5085 1060);
FORCEPROP 0 LASTPIN (-5075 1200) $PN FJ16
J 2
(-5085 1210);
DISPLAY 0.680851 (-5085 1210);
PAINT MONO (-5085 1210);
FORCEPROP 0 LASTPIN (-3825 2100) $PN FF11
J 0
(-3815 2110);
DISPLAY 0.680851 (-3815 2110);
PAINT MONO (-3815 2110);
FORCEPROP 0 LASTPIN (-3825 2700) $PN E11
J 0
(-3815 2710);
DISPLAY 0.680851 (-3815 2710);
PAINT MONO (-3815 2710);
FORCEPROP 0 LASTPIN (-3825 2600) $PN FF33
J 0
(-3815 2610);
DISPLAY 0.680851 (-3815 2610);
PAINT MONO (-3815 2610);
FORCEPROP 0 LASTPIN (-5075 2650) $PN F34
J 2
(-5085 2660);
DISPLAY 0.680851 (-5085 2660);
PAINT MONO (-5085 2660);
FORCEPROP 0 LASTPIN (-5075 2550) $PN B23
J 2
(-5085 2560);
DISPLAY 0.680851 (-5085 2560);
PAINT MONO (-5085 2560);
FORCEPROP 0 LASTPIN (-5075 2450) $PN B25
J 2
(-5085 2460);
DISPLAY 0.680851 (-5085 2460);
PAINT MONO (-5085 2460);
FORCEPROP 0 LASTPIN (-5075 2900) $PN B31
J 2
(-5085 2910);
DISPLAY 0.680851 (-5085 2910);
PAINT MONO (-5085 2910);
FORCEPROP 0 LASTPIN (-5075 2800) $PN B28
J 2
(-5085 2810);
DISPLAY 0.680851 (-5085 2810);
PAINT MONO (-5085 2810);
FORCEPROP 0 LASTPIN (-3825 1700) $PN E30
J 0
(-3815 1710);
DISPLAY 0.680851 (-3815 1710);
PAINT MONO (-3815 1710);
FORCEPROP 0 LASTPIN (-5075 2150) $PN FF24
J 2
(-5085 2160);
DISPLAY 0.680851 (-5085 2160);
PAINT MONO (-5085 2160);
FORCEPROP 0 LASTPIN (-5075 2050) $PN FF27
J 2
(-5085 2060);
DISPLAY 0.680851 (-5085 2060);
PAINT MONO (-5085 2060);
FORCEPROP 0 LASTPIN (-5075 1950) $PN FF30
J 2
(-5085 1960);
DISPLAY 0.680851 (-5085 1960);
PAINT MONO (-5085 1960);
FORCEPROP 1 LAST MATERIAL IC
J 0
(-4925 3825);
DISPLAY 0.723404 (-4925 3825);
PAINT GREEN (-4925 3825);
FORCEPROP 2 LAST VALUE PT5161LRS
J 0
(-4925 4025);
DISPLAY 0.680851 (-4925 4025);
FORCEPROP 2 LAST PART_TYPE SMLF
J 0
(-4925 4075);
DISPLAY 0.680851 (-4925 4075);
FORCEPROP 1 LAST NEEDS_NO_SIZE TRUE
J 0
(-4425 2350);
DISPLAY 0.723404 (-4425 2350);
PAINT GREEN (-4425 2350);
DISPLAY INVISIBLE (-4425 2350);
FORCEPROP 1 LAST CDS_LMAN_SYM_OUTLINE -500,1450,450,-1400
J 0
(-4425 2350);
DISPLAY 0.468085 (-4425 2350);
PAINT GREEN (-4425 2350);
DISPLAY INVISIBLE (-4425 2350);
FORCEPROP 2 LAST CDS_LIB pure_quanta
J 0
(-4425 2350);
DISPLAY INVISIBLE (-4425 2350);
FORCEPROP 1 LAST PATH I97
J 0
(-4425 2350);
DISPLAY 0.723404 (-4425 2350);
PAINT GREEN (-4425 2350);
DISPLAY INVISIBLE (-4425 2350);
FORCEPROP 1 LAST PART_NUMBER AJ051610U03
J 0
(-4925 3900);
DISPLAY 0.723404 (-4925 3900);
PAINT GREEN (-4925 3900);
DISPLAY INVISIBLE (-4925 3900);
FORCEADD Q_RES..1
(-2725 2300);
FORCEPROP 1 LAST LOCATION R1433
J 0
(-2775 2350);
DISPLAY 0.978723 (-2775 2350);
FORCEPROP 0 LAST $SEC 1
J 0
(-2775 2400);
DISPLAY 0.680851 (-2775 2400);
PAINT MONO (-2775 2400);
DISPLAY INVISIBLE (-2775 2400);
FORCEPROP 0 LAST CDS_SEC 1
J 0
(-2775 2400);
DISPLAY 0.680851 (-2775 2400);
DISPLAY INVISIBLE (-2775 2400);
FORCEPROP 1 LASTPIN (-2825 2300) $PN 1
J 0
(-2813 2312);
DISPLAY 0.787234 (-2813 2312);
PAINT MONO (-2813 2312);
FORCEPROP 1 LASTPIN (-2625 2300) $PN 2
J 0
(-2663 2312);
DISPLAY 0.787234 (-2663 2312);
PAINT MONO (-2663 2312);
FORCEPROP 1 LAST MATERIAL CHIP
J 0
(-2450 2300);
DISPLAY 0.638298 (-2450 2300);
FORCEPROP 1 LAST VALUE 4.7K
J 2
(-2475 2300);
DISPLAY 0.638298 (-2475 2300);
FORCEPROP 1 LAST PACK_TYPE 0201LF
J 0
(-2300 2300);
DISPLAY 0.638298 (-2300 2300);
FORCEPROP 1 LAST WATTAGE 1/20W
J 2
(-2750 2150);
DISPLAY 0.978723 (-2750 2150);
DISPLAY INVISIBLE (-2750 2150);
FORCEPROP 1 LAST TOLERANCE 5%
J 0
(-2725 2200);
DISPLAY 0.978723 (-2725 2200);
DISPLAY INVISIBLE (-2725 2200);
FORCEPROP 2 LAST CDS_LIB pure_quanta
J 0
(-2725 2300);
DISPLAY INVISIBLE (-2725 2300);
FORCEPROP 1 LAST PATH I98
J 0
(-2775 2450);
DISPLAY 0.978723 (-2775 2450);
PAINT WHITE (-2775 2450);
DISPLAY INVISIBLE (-2775 2450);
FORCEPROP 1 LAST PART_NUMBER CS24701JE04
J 0
(-2775 2400);
DISPLAY 0.978723 (-2775 2400);
DISPLAY INVISIBLE (-2775 2400);
FORCEADD DNS..1
(-500 1375);
PAINT RED (-500 1375);
FORCEPROP 2 LAST CDS_LIB mstr_misc
J 0
(-500 1375);
DISPLAY INVISIBLE (-500 1375);
FORCEPROP 1 LAST COMMENT_BODY TRUE
R 1
J 0
(-425 1150);
DISPLAY 0.872340 (-425 1150);
PAINT GREEN (-425 1150);
DISPLAY INVISIBLE (-425 1150);
FORCEADD DNS..1
(-1375 1400);
PAINT RED (-1375 1400);
FORCEPROP 2 LAST CDS_LIB mstr_misc
J 0
(-1375 1400);
DISPLAY INVISIBLE (-1375 1400);
FORCEPROP 1 LAST COMMENT_BODY TRUE
R 1
J 0
(-1300 1175);
DISPLAY 0.872340 (-1300 1175);
PAINT GREEN (-1300 1175);
DISPLAY INVISIBLE (-1300 1175);
FORCEADD DNS..1
(-1075 1350);
PAINT RED (-1075 1350);
FORCEPROP 2 LAST CDS_LIB mstr_misc
J 0
(-1075 1350);
DISPLAY INVISIBLE (-1075 1350);
FORCEPROP 1 LAST COMMENT_BODY TRUE
R 1
J 0
(-1000 1125);
DISPLAY 0.872340 (-1000 1125);
PAINT GREEN (-1000 1125);
DISPLAY INVISIBLE (-1000 1125);
FORCEADD DNS..1
(-775 1375);
PAINT RED (-775 1375);
FORCEPROP 2 LAST CDS_LIB mstr_misc
J 0
(-775 1375);
DISPLAY INVISIBLE (-775 1375);
FORCEPROP 1 LAST COMMENT_BODY TRUE
R 1
J 0
(-700 1150);
DISPLAY 0.872340 (-700 1150);
PAINT GREEN (-700 1150);
DISPLAY INVISIBLE (-700 1150);
FORCEADD QUANTA_TITLE_BLOCK_C..1
(0 0);
FORCEPROP 0 LAST CDS_CON_LAST_MODIFIED Thu Sep 14 16:13:06 2023
J 0
(-1885 15);
DISPLAY INVISIBLE (-1885 15);
FORCEPROP 1 LAST CUSTOM_TXT_CDS <CON_LAST_MODIFIED>
J 0
(-1885 15);
DISPLAY 0.978723 (-1885 15);
FORCEPROP 2 LAST CUSTOM_TXT_CDS <XR_PAGE_TITLE>
J 0
(-7890 5250);
DISPLAY 0.638298 (-7890 5250);
PAINT PINK (-7890 5250);
DISPLAY INVISIBLE (-7890 5250);
FORCEPROP 1 LAST CUSTOM_TXT_CDS <NAME_2>
J 0
(-3175 50);
FORCEPROP 1 LAST CUSTOM_TXT_CDS <NAME_1>
J 0
(-3175 175);
FORCEPROP 1 LAST CUSTOM_TXT_CDS <Q_NUMBER>
J 0
(-1403 103);
DISPLAY 1.212766 (-1403 103);
FORCEPROP 1 LAST CUSTOM_TXT_CDS <Q_PROJ>
J 0
(-2382 102);
DISPLAY 1.212766 (-2382 102);
FORCEPROP 1 LAST CUSTOM_TXT_CDS <Q_REV>
J 0
(-184 103);
DISPLAY 1.212766 (-184 103);
FORCEPROP 1 LAST CUSTOM_TXT_CDS <CON_PAGE_NUM> OF <CON_TOTAL_PAGES>
J 0
(-446 18);
DISPLAY 0.978723 (-446 18);
FORCEPROP 1 LAST Q_TITLE RETIMER_CPU1_P3(5)
J 0
(-9366 26);
DISPLAY 2.446809 (-9366 26);
PAINT GREEN (-9366 26);
FORCEPROP 2 LAST CDS_LIB pure_quanta
J 0
(0 0);
DISPLAY INVISIBLE (0 0);
FORCEPROP 1 LAST CDS_LMAN_SYM_OUTLINE -9475,6775,100,-125
J 0
(0 0);
DISPLAY 0.468085 (0 0);
PAINT GREEN (0 0);
DISPLAY INVISIBLE (0 0);
FORCEPROP 2 LAST PAGE_BORDER TRUE
J 0
(-7890 5250);
DISPLAY 0.638298 (-7890 5250);
PAINT PINK (-7890 5250);
DISPLAY INVISIBLE (-7890 5250);
FORCEPROP 2 LAST CDS_XR_PAGE_TITLE CR-354 : @T6G_MB_LIB.T6G(SCH_1):PAGE354
J 0
(-7890 5250);
DISPLAY 0.638298 (-7890 5250);
PAINT PINK (-7890 5250);
DISPLAY INVISIBLE (-7890 5250);
FORCEPROP 1 LAST Q_DEPT BU9
J 1
(-3763 49);
DISPLAY 1.957447 (-3763 49);
PAINT GREEN (-3763 49);
DISPLAY INVISIBLE (-3763 49);
FORCEPROP 1 LAST COMMENT_BODY TRUE
J 0
(12 -13);
DISPLAY 0.978723 (12 -13);
PAINT GREEN (12 -13);
DISPLAY INVISIBLE (12 -13);
FORCEADD DNS..1
(-1525 6075);
PAINT RED (-1525 6075);
FORCEPROP 2 LAST CDS_LIB mstr_misc
J 0
(-1525 6075);
DISPLAY INVISIBLE (-1525 6075);
FORCEPROP 1 LAST COMMENT_BODY TRUE
R 1
J 0
(-1450 5850);
DISPLAY 0.872340 (-1450 5850);
PAINT GREEN (-1450 5850);
DISPLAY INVISIBLE (-1450 5850);
FORCEADD DNS..1
(-2975 6100);
PAINT RED (-2975 6100);
FORCEPROP 2 LAST CDS_LIB mstr_misc
J 0
(-2975 6100);
DISPLAY INVISIBLE (-2975 6100);
FORCEPROP 1 LAST COMMENT_BODY TRUE
R 1
J 0
(-2900 5875);
DISPLAY 0.872340 (-2900 5875);
PAINT GREEN (-2900 5875);
DISPLAY INVISIBLE (-2900 5875);
FORCEADD DNS..1
(-3325 6125);
PAINT RED (-3325 6125);
FORCEPROP 2 LAST CDS_LIB mstr_misc
J 0
(-3325 6125);
DISPLAY INVISIBLE (-3325 6125);
FORCEPROP 1 LAST COMMENT_BODY TRUE
R 1
J 0
(-3250 5900);
DISPLAY 0.872340 (-3250 5900);
PAINT GREEN (-3250 5900);
DISPLAY INVISIBLE (-3250 5900);
FORCEADD DNS..1
(-3625 5300);
PAINT RED (-3625 5300);
FORCEPROP 2 LAST CDS_LIB mstr_misc
J 0
(-3625 5300);
DISPLAY INVISIBLE (-3625 5300);
FORCEPROP 1 LAST COMMENT_BODY TRUE
R 1
J 0
(-3550 5075);
DISPLAY 0.872340 (-3550 5075);
PAINT GREEN (-3550 5075);
DISPLAY INVISIBLE (-3550 5075);
FORCEADD DNS..1
(-5000 5500);
PAINT RED (-5000 5500);
FORCEPROP 2 LAST CDS_LIB mstr_misc
J 0
(-5000 5500);
DISPLAY INVISIBLE (-5000 5500);
FORCEPROP 1 LAST COMMENT_BODY TRUE
R 1
J 0
(-4925 5275);
DISPLAY 0.872340 (-4925 5275);
PAINT GREEN (-4925 5275);
DISPLAY INVISIBLE (-4925 5275);
FORCEADD DNS..1
(-6125 750);
PAINT RED (-6125 750);
FORCEPROP 2 LAST CDS_LIB mstr_misc
J 0
(-6125 750);
DISPLAY INVISIBLE (-6125 750);
FORCEPROP 1 LAST COMMENT_BODY TRUE
R 1
J 0
(-6050 525);
DISPLAY 0.872340 (-6050 525);
PAINT GREEN (-6050 525);
DISPLAY INVISIBLE (-6050 525);
FORCEADD DNS..1
(-6475 725);
PAINT RED (-6475 725);
FORCEPROP 2 LAST CDS_LIB mstr_misc
J 0
(-6475 725);
DISPLAY INVISIBLE (-6475 725);
FORCEPROP 1 LAST COMMENT_BODY TRUE
R 1
J 0
(-6400 500);
DISPLAY 0.872340 (-6400 500);
PAINT GREEN (-6400 500);
DISPLAY INVISIBLE (-6400 500);
FORCEADD DNS..1
(-7375 5975);
PAINT RED (-7375 5975);
FORCEPROP 2 LAST CDS_LIB mstr_misc
J 0
(-7375 5975);
DISPLAY INVISIBLE (-7375 5975);
FORCEPROP 1 LAST COMMENT_BODY TRUE
R 1
J 0
(-7300 5750);
DISPLAY 0.872340 (-7300 5750);
PAINT GREEN (-7300 5750);
DISPLAY INVISIBLE (-7300 5750);
FORCEADD DNS..1
(-7700 6025);
PAINT RED (-7700 6025);
FORCEPROP 2 LAST CDS_LIB mstr_misc
J 0
(-7700 6025);
DISPLAY INVISIBLE (-7700 6025);
FORCEPROP 1 LAST COMMENT_BODY TRUE
R 1
J 0
(-7625 5800);
DISPLAY 0.872340 (-7625 5800);
PAINT GREEN (-7625 5800);
DISPLAY INVISIBLE (-7625 5800);
FORCEADD DNS..1
(-7975 5975);
PAINT RED (-7975 5975);
FORCEPROP 2 LAST CDS_LIB mstr_misc
J 0
(-7975 5975);
DISPLAY INVISIBLE (-7975 5975);
FORCEPROP 1 LAST COMMENT_BODY TRUE
R 1
J 0
(-7900 5750);
DISPLAY 0.872340 (-7900 5750);
PAINT GREEN (-7900 5750);
DISPLAY INVISIBLE (-7900 5750);
FORCEADD DNS..1
(-8275 6000);
PAINT RED (-8275 6000);
FORCEPROP 2 LAST CDS_LIB mstr_misc
J 0
(-8275 6000);
DISPLAY INVISIBLE (-8275 6000);
FORCEPROP 1 LAST COMMENT_BODY TRUE
R 1
J 0
(-8200 5775);
DISPLAY 0.872340 (-8200 5775);
PAINT GREEN (-8200 5775);
DISPLAY INVISIBLE (-8200 5775);
FORCEADD DNS..1
(-8875 5975);
PAINT RED (-8875 5975);
FORCEPROP 2 LAST CDS_LIB mstr_misc
J 0
(-8875 5975);
DISPLAY INVISIBLE (-8875 5975);
FORCEPROP 1 LAST COMMENT_BODY TRUE
R 1
J 0
(-8800 5750);
DISPLAY 0.872340 (-8800 5750);
PAINT GREEN (-8800 5750);
DISPLAY INVISIBLE (-8800 5750);
FORCEADD DNS..1
(-8975 4100);
PAINT RED (-8975 4100);
FORCEPROP 2 LAST CDS_LIB mstr_misc
J 0
(-8975 4100);
DISPLAY INVISIBLE (-8975 4100);
FORCEPROP 1 LAST COMMENT_BODY TRUE
R 1
J 0
(-8900 3875);
DISPLAY 0.872340 (-8900 3875);
PAINT GREEN (-8900 3875);
DISPLAY INVISIBLE (-8900 3875);
FORCEADD DNS..1
(-1450 3725);
PAINT RED (-1450 3725);
FORCEPROP 2 LAST CDS_LIB mstr_misc
J 0
(-1450 3725);
DISPLAY INVISIBLE (-1450 3725);
FORCEPROP 1 LAST COMMENT_BODY TRUE
R 1
J 0
(-1375 3500);
DISPLAY 0.872340 (-1375 3500);
PAINT GREEN (-1375 3500);
DISPLAY INVISIBLE (-1375 3500);
WIRE 16 -1 (-2625 2300)(-2050 2300);
WIRE 16 -1 (-1525 3100)(-1525 2850);
WIRE 16 -1 (-2650 3250)(-2050 3250);
WIRE 16 -1 (-1525 3825)(-1525 4075);
WIRE 16 -1 (-575 625)(-575 475);
WIRE 16 -1 (-9025 3350)(-9025 3225);
WIRE 16 -1 (-9025 4225)(-9025 4400);
WIRE 16 -1 (-6350 625)(-6350 450);
WIRE 16 -1 (-6200 625)(-6200 450);
WIRE 16 -1 (-5075 5450)(-5075 5250);
WIRE 16 -1 (-5075 6175)(-5075 6350);
WIRE 16 -1 (-3825 1700)(-2725 1700);
WIRE 16 -1 (-1525 5125)(-1525 4900);
WIRE 16 -1 (-1350 5125)(-1350 4925);
WIRE 16 -1 (-1525 6250)(-1525 6150);
WIRE 16 -1 (-6475 1650)(-7700 1650);
FORCEPROP 2 LAST SIG_NAME SMB_RT_CPU1_P3_ROM_MUX_1D_SCL
J 0
(-7610 1660);
DISPLAY 0.680851 (-7610 1660);
PAINT SKYBLUE (-7610 1660);
WIRE 16 -1 (-5075 1650)(-6275 1650);
FORCEPROP 2 LAST SIG_NAME SMB_RT_CPU1_P3_ROM_MUX_1D_R_SCL
J 0
(-6210 1675);
DISPLAY 0.680851 (-6210 1675);
PAINT SKYBLUE (-6210 1675);
FORCEPROP 2 LASTPROP $XRERR UNIQUE?
J 0
(-6450 1675);
DISPLAY 0.638298 (-6450 1675);
PAINT MONO (-6450 1675);
DISPLAY INVISIBLE (-6450 1675);
WIRE 16 -1 (-5075 2150)(-6150 2150);
FORCEPROP 2 LAST SIG_NAME TEST0_RT_CPU1_P3
J 0
(-5835 2160);
DISPLAY 0.680851 (-5835 2160);
PAINT SKYBLUE (-5835 2160);
WIRE 16 -1 (-5075 1550)(-6275 1550);
FORCEPROP 2 LAST SIG_NAME SMB_RT_CPU1_P3_ROM_MUX_1D_R_SDA
J 0
(-6210 1575);
DISPLAY 0.680851 (-6210 1575);
PAINT SKYBLUE (-6210 1575);
FORCEPROP 2 LASTPROP $XRERR UNIQUE?
J 0
(-6450 1575);
DISPLAY 0.638298 (-6450 1575);
PAINT MONO (-6450 1575);
DISPLAY INVISIBLE (-6450 1575);
WIRE 16 -1 (-6475 1550)(-7675 1550);
FORCEPROP 2 LAST SIG_NAME SMB_RT_CPU1_P3_ROM_MUX_1D_SDA
J 0
(-7610 1560);
DISPLAY 0.680851 (-7610 1560);
PAINT SKYBLUE (-7610 1560);
WIRE 16 -1 (-7900 3900)(-9025 3900);
FORCEPROP 2 LAST SIG_NAME RT_CPU1_P3_SCAN_MODE
J 0
(-8635 3910);
DISPLAY 0.680851 (-8635 3910);
PAINT SKYBLUE (-8635 3910);
WIRE 16 -1 (-9025 4025)(-9025 3900);
WIRE 16 -1 (-9025 3900)(-9025 3550);
WIRE 16 -1 (-1400 1450)(-1400 1600);
WIRE 16 -1 (-1400 1600)(-1125 1600);
WIRE 16 -1 (-1125 1600)(-850 1600);
WIRE 16 -1 (-1125 1450)(-1125 1600);
WIRE 16 -1 (-850 1600)(-575 1600);
WIRE 16 -1 (-850 1450)(-850 1600);
WIRE 16 -1 (-575 1475)(-575 1600);
WIRE 16 -1 (-575 1600)(-575 1625);
WIRE 16 -1 (-7775 6300)(-7475 6300);
WIRE 16 -1 (-7775 6300)(-8075 6300);
WIRE 16 -1 (-7775 6300)(-7775 6075);
WIRE 16 -1 (-7475 6300)(-7475 6100);
WIRE 16 -1 (-8075 6300)(-8075 6050);
WIRE 16 -1 (-8075 6300)(-8375 6300);
WIRE 16 -1 (-9000 6300)(-8375 6300);
WIRE 16 -1 (-8375 6300)(-8375 6100);
WIRE 16 -1 (-9000 6350)(-9000 6300);
WIRE 16 -1 (-9000 6300)(-9000 6100);
WIRE 16 -1 (-9000 4950)(-9000 4725);
WIRE 16 -1 (-9000 4725)(-8700 4725);
WIRE 16 -1 (-8700 4725)(-8375 4725);
WIRE 16 -1 (-8700 4950)(-8700 4725);
WIRE 16 -1 (-8075 4725)(-8375 4725);
WIRE 16 -1 (-8375 4950)(-8375 4725);
WIRE 16 -1 (-7775 4725)(-8075 4725);
WIRE 16 -1 (-8075 4925)(-8075 4725);
WIRE 16 -1 (-7775 4725)(-7475 4725);
WIRE 16 -1 (-7775 4925)(-7775 4725);
WIRE 16 -1 (-7475 4900)(-7475 4725);
WIRE 16 -1 (-7475 4725)(-7475 4600);
WIRE 16 -1 (-3025 5225)(-3025 5050);
WIRE 16 -1 (-3025 5050)(-3375 5050);
WIRE 16 -1 (-3375 5225)(-3375 5050);
WIRE 16 -1 (-3375 5050)(-3675 5050);
WIRE 16 -1 (-3675 5225)(-3675 5050);
WIRE 16 -1 (-3675 5050)(-3675 4950);
WIRE 16 -1 (-3375 6425)(-3025 6425);
WIRE 16 -1 (-3375 6425)(-3375 6200);
WIRE 16 -1 (-3675 6425)(-3375 6425);
WIRE 16 -1 (-3025 6425)(-3025 6175);
WIRE 16 -1 (-3675 6200)(-3675 6425);
WIRE 16 -1 (-3675 6425)(-3675 6475);
WIRE 16 -1 (-1400 1250)(-1400 950);
WIRE 16 -1 (-2500 950)(-1400 950);
FORCEPROP 2 LAST SIG_NAME JTAG_TDI_RT_CPU1_P3
J 0
(-2335 960);
DISPLAY 0.680851 (-2335 960);
PAINT WHITE (-2335 960);
WIRE 16 -1 (-850 1250)(-850 1050);
WIRE 16 -1 (-2500 1050)(-850 1050);
FORCEPROP 2 LAST SIG_NAME JTAG_TDO_RT_CPU1_P3
J 0
(-2310 1060);
DISPLAY 0.680851 (-2310 1060);
PAINT WHITE (-2310 1060);
WIRE 16 -1 (-1125 1250)(-1125 1000);
WIRE 16 -1 (-2500 1000)(-1125 1000);
FORCEPROP 2 LAST SIG_NAME JTAG_TMS_RT_CPU1_P3
J 0
(-2310 1010);
DISPLAY 0.680851 (-2310 1010);
PAINT WHITE (-2310 1010);
WIRE 16 -1 (-575 1275)(-575 1100);
WIRE 16 -1 (-575 1100)(-575 825);
WIRE 16 -1 (-2500 1100)(-575 1100);
FORCEPROP 2 LAST SIG_NAME JTAG_TCK_RT_CPU1_P3
J 0
(-2335 1110);
DISPLAY 0.680851 (-2335 1110);
PAINT WHITE (-2335 1110);
WIRE 16 -1 (-2525 2100)(-1150 2100);
FORCEPROP 2 LAST SIG_NAME RST_RT_CPU1_P3_RESET_R_N
J 0
(-2010 2110);
DISPLAY 0.680851 (-2010 2110);
PAINT SKYBLUE (-2010 2110);
WIRE 16 -1 (-2525 2200)(-1150 2200);
FORCEPROP 2 LAST SIG_NAME RST_RT_CPU1_P3_PERST_R_N
J 0
(-1985 2210);
DISPLAY 0.680851 (-1985 2210);
PAINT SKYBLUE (-1985 2210);
WIRE 16 -1 (-3825 3350)(-2850 3350);
FORCEPROP 2 LAST SIG_NAME JTAG_TDI_RT_CPU1_P3
J 0
(-3660 3360);
DISPLAY 0.680851 (-3660 3360);
PAINT WHITE (-3660 3360);
WIRE 16 -1 (-3825 3450)(-2825 3450);
FORCEPROP 2 LAST SIG_NAME JTAG_TMS_RT_CPU1_P3
J 0
(-3635 3460);
DISPLAY 0.680851 (-3635 3460);
PAINT WHITE (-3635 3460);
WIRE 16 -1 (-3825 3550)(-2825 3550);
FORCEPROP 2 LAST SIG_NAME JTAG_TDO_RT_CPU1_P3
J 0
(-3635 3560);
DISPLAY 0.680851 (-3635 3560);
PAINT WHITE (-3635 3560);
WIRE 16 -1 (-3825 3650)(-2825 3650);
FORCEPROP 2 LAST SIG_NAME JTAG_TCK_RT_CPU1_P3
J 0
(-3660 3660);
DISPLAY 0.680851 (-3660 3660);
PAINT WHITE (-3660 3660);
WIRE 16 -1 (-3825 3250)(-2850 3250);
FORCEPROP 2 LAST SIG_NAME JTAG_TRST_RT_CPU1_P3_N
J 0
(-3660 3260);
DISPLAY 0.680851 (-3660 3260);
PAINT WHITE (-3660 3260);
FORCEPROP 2 LASTPROP $XRERR UNIQUE?
J 0
(-3900 3260);
DISPLAY 0.638298 (-3900 3260);
PAINT MONO (-3900 3260);
DISPLAY INVISIBLE (-3900 3260);
WIRE 16 -1 (-3825 3100)(-2575 3100);
FORCEPROP 2 LAST SIG_NAME JTAG_TEST_MODE_RT_CPU1_P3
J 0
(-3635 3110);
DISPLAY 0.680851 (-3635 3110);
PAINT SKYBLUE (-3635 3110);
WIRE 16 -1 (-3825 2800)(-2500 2800);
FORCEPROP 2 LAST SIG_NAME MODE_RT_CPU1_P3
J 0
(-3510 2810);
DISPLAY 0.680851 (-3510 2810);
PAINT SKYBLUE (-3510 2810);
WIRE 16 -1 (-3825 2700)(-2500 2700);
FORCEPROP 2 LAST SIG_NAME RXDET_BYP_RT_CPU1_P3
J 0
(-3510 2710);
DISPLAY 0.680851 (-3510 2710);
PAINT WHITE (-3510 2710);
WIRE 16 -1 (-3825 2600)(-2475 2600);
FORCEPROP 2 LAST SIG_NAME RT_CPU1_P3_SCAN_MODE
J 0
(-3535 2610);
DISPLAY 0.680851 (-3535 2610);
PAINT SKYBLUE (-3535 2610);
WIRE 16 -1 (-3825 2100)(-2725 2100);
FORCEPROP 2 LAST SIG_NAME RST_RT_CPU1_P3_RESET_N
J 0
(-3635 2110);
DISPLAY 0.680851 (-3635 2110);
PAINT SKYBLUE (-3635 2110);
FORCEPROP 2 LASTPROP $XRERR UNIQUE?
J 0
(-3875 2110);
DISPLAY 0.638298 (-3875 2110);
PAINT MONO (-3875 2110);
DISPLAY INVISIBLE (-3875 2110);
WIRE 16 -1 (-3825 2200)(-2725 2200);
FORCEPROP 2 LAST SIG_NAME RST_RT_CPU1_P3_PERST_N
J 0
(-3660 2210);
DISPLAY 0.680851 (-3660 2210);
PAINT SKYBLUE (-3660 2210);
FORCEPROP 2 LASTPROP $XRERR UNIQUE?
J 0
(-3900 2210);
DISPLAY 0.638298 (-3900 2210);
PAINT MONO (-3900 2210);
DISPLAY INVISIBLE (-3900 2210);
WIRE 16 -1 (-3825 2300)(-2825 2300);
FORCEPROP 2 LAST SIG_NAME CLKREQ_RT_CPU1_P3_N
J 0
(-3560 2310);
DISPLAY 0.680851 (-3560 2310);
PAINT WHITE (-3560 2310);
FORCEPROP 2 LASTPROP $XRERR UNIQUE?
J 0
(-3800 2310);
DISPLAY 0.638298 (-3800 2310);
PAINT MONO (-3800 2310);
DISPLAY INVISIBLE (-3800 2310);
WIRE 16 -1 (-5075 3250)(-6025 3250);
FORCEPROP 2 LAST SIG_NAME GPIO3_RT_CPU1_P3
J 0
(-5885 3260);
DISPLAY 0.680851 (-5885 3260);
PAINT SKYBLUE (-5885 3260);
WIRE 16 -1 (-5075 3350)(-6025 3350);
FORCEPROP 2 LAST SIG_NAME GPIO2_RT_CPU1_P3
J 0
(-5885 3360);
DISPLAY 0.680851 (-5885 3360);
PAINT SKYBLUE (-5885 3360);
WIRE 16 -1 (-1525 3300)(-1525 3450);
WIRE 16 -1 (-725 3450)(-1525 3450);
FORCEPROP 2 LAST SIG_NAME RXDET_BYP_RT_CPU1_P3
J 0
(-1410 3460);
DISPLAY 0.680851 (-1410 3460);
PAINT WHITE (-1410 3460);
WIRE 16 -1 (-1525 3450)(-1525 3625);
WIRE 16 -1 (-5075 2800)(-6300 2800);
FORCEPROP 2 LAST SIG_NAME SMB_RT_CPU1_P3_R2_SDA
J 0
(-6060 2810);
DISPLAY 0.680851 (-6060 2810);
PAINT SKYBLUE (-6060 2810);
FORCEPROP 2 LASTPROP $XRERR UNIQUE?
J 0
(-6300 2810);
DISPLAY 0.638298 (-6300 2810);
PAINT MONO (-6300 2810);
DISPLAY INVISIBLE (-6300 2810);
WIRE 16 -1 (-5075 2900)(-6300 2900);
FORCEPROP 2 LAST SIG_NAME SMB_RT_CPU1_P3_R2_SCL
J 0
(-6060 2910);
DISPLAY 0.680851 (-6060 2910);
PAINT SKYBLUE (-6060 2910);
FORCEPROP 2 LASTPROP $XRERR UNIQUE?
J 0
(-6300 2910);
DISPLAY 0.638298 (-6300 2910);
PAINT MONO (-6300 2910);
DISPLAY INVISIBLE (-6300 2910);
WIRE 16 -1 (-1525 5325)(-1525 5600);
WIRE 16 -1 (-600 5600)(-1525 5600);
FORCEPROP 2 LAST SIG_NAME RST_RT_CPU1_P3_RESET_R_N
J 0
(-1485 5635);
DISPLAY 0.680851 (-1485 5635);
PAINT SKYBLUE (-1485 5635);
WIRE 16 -1 (-1525 5950)(-1525 5600);
WIRE 16 -1 (-1350 5450)(-625 5450);
WIRE 16 -1 (-1350 5325)(-1350 5450);
FORCEPROP 2 LAST SIG_NAME RST_RT_CPU1_P3_PERST_R_N
J 0
(-1385 5485);
DISPLAY 0.680851 (-1385 5485);
PAINT SKYBLUE (-1385 5485);
WIRE 16 -1 (-3375 5425)(-3375 5675);
WIRE 16 -1 (-2175 5675)(-3375 5675);
FORCEPROP 2 LAST SIG_NAME RT_CPU1_P3_ADDR2
J 0
(-2960 5685);
DISPLAY 0.680851 (-2960 5685);
PAINT SKYBLUE (-2960 5685);
WIRE 16 -1 (-3375 5675)(-3375 6000);
WIRE 16 -1 (-2175 5775)(-3675 5775);
FORCEPROP 2 LAST SIG_NAME RT_CPU1_P3_ADDR3
J 0
(-2960 5810);
DISPLAY 0.680851 (-2960 5810);
PAINT SKYBLUE (-2960 5810);
WIRE 16 -1 (-3675 6000)(-3675 5775);
WIRE 16 -1 (-3675 5775)(-3675 5425);
WIRE 16 -1 (-5075 5650)(-5075 5800);
WIRE 16 -1 (-4250 5800)(-5075 5800);
FORCEPROP 2 LAST SIG_NAME MODE_RT_CPU1_P3
J 0
(-4860 5810);
DISPLAY 0.680851 (-4860 5810);
PAINT SKYBLUE (-4860 5810);
WIRE 16 -1 (-5075 5975)(-5075 5800);
WIRE 16 -1 (-6475 5400)(-7475 5400);
FORCEPROP 2 LAST SIG_NAME JTAG_TEST_MODE_RT_CPU1_P3
J 0
(-7285 5410);
DISPLAY 0.680851 (-7285 5410);
PAINT SKYBLUE (-7285 5410);
WIRE 16 -1 (-7475 5900)(-7475 5400);
WIRE 16 -1 (-7475 5400)(-7475 5100);
WIRE 16 -1 (-7775 5125)(-7775 5475);
WIRE 16 -1 (-6475 5475)(-7775 5475);
FORCEPROP 2 LAST SIG_NAME TEST2_RT_CPU1_P3
J 0
(-7035 5485);
DISPLAY 0.680851 (-7035 5485);
PAINT SKYBLUE (-7035 5485);
WIRE 16 -1 (-7775 5875)(-7775 5475);
WIRE 16 -1 (-8075 5125)(-8075 5525);
WIRE 16 -1 (-6475 5525)(-8075 5525);
FORCEPROP 2 LAST SIG_NAME TEST1_RT_CPU1_P3
J 0
(-7035 5535);
DISPLAY 0.680851 (-7035 5535);
PAINT SKYBLUE (-7035 5535);
WIRE 16 -1 (-8075 5850)(-8075 5525);
WIRE 16 -1 (-8375 5150)(-8375 5575);
WIRE 16 -1 (-6475 5575)(-8375 5575);
FORCEPROP 2 LAST SIG_NAME TEST0_RT_CPU1_P3
J 0
(-7035 5585);
DISPLAY 0.680851 (-7035 5585);
PAINT SKYBLUE (-7035 5585);
WIRE 16 -1 (-8375 5900)(-8375 5575);
WIRE 16 -1 (-9000 5150)(-9000 5700);
WIRE 16 -1 (-6475 5700)(-9000 5700);
FORCEPROP 2 LAST SIG_NAME GPIO2_RT_CPU1_P3
J 0
(-7035 5710);
DISPLAY 0.680851 (-7035 5710);
PAINT SKYBLUE (-7035 5710);
WIRE 16 -1 (-9000 5900)(-9000 5700);
WIRE 16 -1 (-6500 2900)(-7650 2900);
FORCEPROP 2 LAST SIG_NAME SMB_RT_CPU1_P3_R_SCL
J 0
(-7485 2910);
DISPLAY 0.680851 (-7485 2910);
PAINT SKYBLUE (-7485 2910);
WIRE 16 -1 (-6475 5625)(-8700 5625);
FORCEPROP 2 LAST SIG_NAME GPIO3_RT_CPU1_P3
J 0
(-7060 5635);
DISPLAY 0.680851 (-7060 5635);
PAINT SKYBLUE (-7060 5635);
WIRE 16 -1 (-8700 5625)(-8700 5150);
WIRE 16 -1 (-5075 2650)(-5975 2650);
FORCEPROP 2 LAST SIG_NAME RT_CPU1_P3_ADDR1
J 0
(-5835 2660);
DISPLAY 0.680851 (-5835 2660);
PAINT SKYBLUE (-5835 2660);
WIRE 16 -1 (-5075 2450)(-5975 2450);
FORCEPROP 2 LAST SIG_NAME RT_CPU1_P3_ADDR3
J 0
(-5835 2460);
DISPLAY 0.680851 (-5835 2460);
PAINT SKYBLUE (-5835 2460);
WIRE 16 -1 (-5075 2550)(-5975 2550);
FORCEPROP 2 LAST SIG_NAME RT_CPU1_P3_ADDR2
J 0
(-5835 2560);
DISPLAY 0.680851 (-5835 2560);
PAINT SKYBLUE (-5835 2560);
WIRE 16 -1 (-3025 5425)(-3025 5575);
WIRE 16 -1 (-2175 5575)(-3025 5575);
FORCEPROP 2 LAST SIG_NAME RT_CPU1_P3_ADDR1
J 0
(-2960 5585);
DISPLAY 0.680851 (-2960 5585);
PAINT SKYBLUE (-2960 5585);
WIRE 16 -1 (-3025 5575)(-3025 5975);
WIRE 16 -1 (-5075 1950)(-6150 1950);
FORCEPROP 2 LAST SIG_NAME TEST2_RT_CPU1_P3
J 0
(-5835 1960);
DISPLAY 0.680851 (-5835 1960);
PAINT SKYBLUE (-5835 1960);
WIRE 16 -1 (-5075 1200)(-6200 1200);
FORCEPROP 2 LAST SIG_NAME CLK_100M_RETIMER_CPU1_P3_DP
J 0
(-6110 1210);
DISPLAY 0.680851 (-6110 1210);
PAINT SKYBLUE (-6110 1210);
FORCEPROP 2 LASTPROP $XRERR UNIQUE?
J 0
(-6350 1210);
DISPLAY 0.638298 (-6350 1210);
PAINT MONO (-6350 1210);
DISPLAY INVISIBLE (-6350 1210);
WIRE 16 -1 (-6200 1200)(-6550 1200);
WIRE 16 -1 (-6200 1200)(-6200 825);
WIRE 16 -1 (-6750 1200)(-8050 1200);
FORCEPROP 2 LAST SIG_NAME CLK_100M_RETIMER_CPU1_P3_R_DP
J 0
(-7985 1210);
DISPLAY 0.680851 (-7985 1210);
PAINT SKYBLUE (-7985 1210);
WIRE 16 -1 (-5075 1050)(-6350 1050);
FORCEPROP 0 LAST SIG_NAME CLK_100M_RETIMER_CPU1_P3_DN
J 0
(-6110 1060);
DISPLAY 0.680851 (-6110 1060);
PAINT SKYBLUE (-6110 1060);
FORCEPROP 2 LASTPROP $XRERR UNIQUE?
J 0
(-6350 1060);
DISPLAY 0.638298 (-6350 1060);
PAINT MONO (-6350 1060);
DISPLAY INVISIBLE (-6350 1060);
WIRE 16 -1 (-6350 1050)(-6550 1050);
WIRE 16 -1 (-6350 1050)(-6350 825);
WIRE 16 -1 (-6750 1050)(-8050 1050);
FORCEPROP 2 LAST SIG_NAME CLK_100M_RETIMER_CPU1_P3_R_DN
J 0
(-8010 1060);
DISPLAY 0.680851 (-8010 1060);
PAINT SKYBLUE (-8010 1060);
WIRE 16 -1 (-6500 2800)(-7650 2800);
FORCEPROP 2 LAST SIG_NAME SMB_RT_CPU1_P3_R_SDA
J 0
(-7485 2810);
DISPLAY 0.680851 (-7485 2810);
PAINT SKYBLUE (-7485 2810);
WIRE 16 -1 (-5075 2050)(-6150 2050);
FORCEPROP 2 LAST SIG_NAME TEST1_RT_CPU1_P3
J 0
(-5835 2060);
DISPLAY 0.680851 (-5835 2060);
PAINT SKYBLUE (-5835 2060);
DOT 1 (-575 1600);
DOT 1 (-575 1100);
DOT 1 (-1125 1600);
DOT 1 (-1525 3450);
DOT 1 (-1525 5600);
DOT 1 (-3375 6425);
DOT 1 (-3675 6425);
DOT 1 (-3025 5575);
DOT 1 (-3375 5675);
DOT 1 (-3675 5775);
DOT 1 (-3675 5050);
DOT 1 (-6200 1200);
DOT 1 (-6350 1050);
DOT 1 (-7775 6300);
DOT 1 (-8075 6300);
DOT 1 (-8375 6300);
DOT 1 (-7775 5475);
DOT 1 (-7475 4725);
DOT 1 (-7775 4725);
DOT 1 (-8075 5525);
DOT 1 (-8375 5575);
DOT 1 (-8075 4725);
DOT 1 (-8375 4725);
DOT 1 (-8700 4725);
DOT 1 (-9000 6300);
DOT 1 (-9000 5700);
DOT 1 (-7475 5400);
DOT 1 (-3375 5050);
DOT 1 (-5075 5800);
DOT 1 (-9025 3900);
DOT 1 (-850 1600);
FORCENOTE
CPU1 P1 RT ADDR: 0X48 (8-BIT) / 0X24 (7-BIT)
(-4325 4625) 0;
DISPLAY LEFT (-4325 4625);
DISPLAY 1.595745 (-4325 4625);
QUIT
